G04*
G04 #@! TF.GenerationSoftware,Altium Limited,Altium Designer,22.4.2 (48)*
G04*
G04 Layer_Physical_Order=5*
G04 Layer_Color=16737945*
%FSLAX25Y25*%
%MOIN*%
G70*
G04*
G04 #@! TF.SameCoordinates,446674BB-F454-490D-8607-5140536C8ADF*
G04*
G04*
G04 #@! TF.FilePolarity,Positive*
G04*
G01*
G75*
%ADD157C,0.05906*%
%ADD159C,0.07500*%
%ADD160C,0.05000*%
%ADD161C,0.09843*%
%ADD164C,0.08661*%
%ADD167C,0.01600*%
%ADD171C,0.01968*%
G36*
X24633Y20107D02*
X24950Y19721D01*
X24943Y19685D01*
X25068Y19061D01*
X25421Y18531D01*
X25951Y18178D01*
X26575Y18054D01*
X27199Y18178D01*
X27728Y18531D01*
X28082Y19061D01*
X28206Y19685D01*
X28199Y19721D01*
X28516Y20107D01*
X31608D01*
X31833Y19833D01*
X31957Y19209D01*
X32311Y18679D01*
X32840Y18326D01*
X33465Y18202D01*
X34089Y18326D01*
X34618Y18679D01*
X34972Y19209D01*
X35096Y19833D01*
X35321Y20107D01*
X38413D01*
X38730Y19721D01*
X38723Y19685D01*
X38847Y19061D01*
X39201Y18531D01*
X39730Y18178D01*
X40354Y18054D01*
X40979Y18178D01*
X41508Y18531D01*
X41862Y19061D01*
X41986Y19685D01*
X41979Y19721D01*
X42296Y20107D01*
X45303D01*
X45620Y19721D01*
X45613Y19685D01*
X45737Y19061D01*
X46091Y18531D01*
X46620Y18178D01*
X47244Y18054D01*
X47868Y18178D01*
X48398Y18531D01*
X48751Y19061D01*
X48875Y19685D01*
X48868Y19721D01*
X49186Y20107D01*
X105117D01*
X699564Y20107D01*
X699564Y-363786D01*
X283662D01*
X283193Y-363879D01*
X282796Y-364144D01*
X282531Y-364541D01*
X282501Y-364693D01*
X282449D01*
X282438Y-365009D01*
X282438Y-365188D01*
Y-392667D01*
X201420D01*
Y-385876D01*
X201412Y-385836D01*
X201418Y-385796D01*
X201386Y-385307D01*
X201355Y-385191D01*
X201347Y-385071D01*
X201094Y-384128D01*
X201023Y-383984D01*
X200972Y-383833D01*
X200483Y-382987D01*
X200378Y-382867D01*
X200289Y-382734D01*
X199599Y-382043D01*
X199466Y-381954D01*
X199345Y-381849D01*
X198500Y-381361D01*
X198348Y-381309D01*
X198205Y-381238D01*
X197262Y-380986D01*
X197102Y-380975D01*
X196945Y-380944D01*
X195968D01*
X195812Y-380975D01*
X195652Y-380986D01*
X195625Y-380993D01*
X194449D01*
X193627Y-381815D01*
X193568Y-381849D01*
X193448Y-381954D01*
X193315Y-382043D01*
X192624Y-382734D01*
X192535Y-382867D01*
X192430Y-382987D01*
X192396Y-383046D01*
X191249Y-384193D01*
Y-392667D01*
X149846D01*
Y-372195D01*
X149840Y-372165D01*
X149844Y-372134D01*
X149809Y-371430D01*
X149787Y-371342D01*
Y-371252D01*
X149513Y-369870D01*
X149467Y-369759D01*
X149443Y-369641D01*
X149149Y-368931D01*
Y-368693D01*
X148981Y-368525D01*
X148904Y-368339D01*
X148837Y-368239D01*
X148791Y-368128D01*
X148008Y-366957D01*
X147923Y-366871D01*
X147856Y-366771D01*
X146860Y-365775D01*
X146760Y-365708D01*
X146675Y-365623D01*
X145504Y-364841D01*
X145392Y-364794D01*
X145292Y-364727D01*
X145107Y-364651D01*
X144549Y-364093D01*
X143631D01*
X142380Y-363844D01*
X142259D01*
X142141Y-363821D01*
X140733D01*
X140615Y-363844D01*
X140494D01*
X139243Y-364093D01*
X137349D01*
X132849Y-368593D01*
Y-383091D01*
X103979D01*
Y-365009D01*
X103886Y-364541D01*
X103621Y-364144D01*
X103224Y-363879D01*
X102756Y-363786D01*
X30512D01*
X30044Y-363879D01*
X29647Y-364144D01*
X29481Y-364393D01*
X29149D01*
Y-396266D01*
X-27320D01*
Y20107D01*
X24633D01*
D02*
G37*
%LPC*%
G36*
X592808Y17690D02*
X585302D01*
Y10184D01*
X592808D01*
Y17690D01*
D02*
G37*
G36*
X579055Y17722D02*
X578076Y17593D01*
X577163Y17215D01*
X576379Y16613D01*
X575777Y15830D01*
X575399Y14917D01*
X575270Y13937D01*
X575399Y12957D01*
X575777Y12044D01*
X576379Y11260D01*
X577163Y10659D01*
X578076Y10281D01*
X579055Y10152D01*
X580035Y10281D01*
X580948Y10659D01*
X581732Y11260D01*
X582333Y12044D01*
X582711Y12957D01*
X582840Y13937D01*
X582711Y14917D01*
X582333Y15830D01*
X581732Y16613D01*
X580948Y17215D01*
X580035Y17593D01*
X579055Y17722D01*
D02*
G37*
G36*
X569055D02*
X568076Y17593D01*
X567163Y17215D01*
X566379Y16613D01*
X565777Y15830D01*
X565399Y14917D01*
X565270Y13937D01*
X565399Y12957D01*
X565777Y12044D01*
X566379Y11260D01*
X567163Y10659D01*
X568076Y10281D01*
X569055Y10152D01*
X570035Y10281D01*
X570948Y10659D01*
X571732Y11260D01*
X572333Y12044D01*
X572711Y12957D01*
X572840Y13937D01*
X572711Y14917D01*
X572333Y15830D01*
X571732Y16613D01*
X570948Y17215D01*
X570035Y17593D01*
X569055Y17722D01*
D02*
G37*
G36*
X559055D02*
X558076Y17593D01*
X557163Y17215D01*
X556379Y16613D01*
X555777Y15830D01*
X555399Y14917D01*
X555270Y13937D01*
X555399Y12957D01*
X555777Y12044D01*
X556379Y11260D01*
X557163Y10659D01*
X558076Y10281D01*
X559055Y10152D01*
X560035Y10281D01*
X560948Y10659D01*
X561732Y11260D01*
X562333Y12044D01*
X562711Y12957D01*
X562840Y13937D01*
X562711Y14917D01*
X562333Y15830D01*
X561732Y16613D01*
X560948Y17215D01*
X560035Y17593D01*
X559055Y17722D01*
D02*
G37*
G36*
X539055D02*
X538075Y17593D01*
X537163Y17215D01*
X536379Y16613D01*
X535777Y15830D01*
X535399Y14917D01*
X535270Y13937D01*
X535399Y12957D01*
X535777Y12044D01*
X536379Y11260D01*
X537163Y10659D01*
X538075Y10281D01*
X539055Y10152D01*
X540035Y10281D01*
X540948Y10659D01*
X541732Y11260D01*
X542333Y12044D01*
X542711Y12957D01*
X542840Y13937D01*
X542711Y14917D01*
X542333Y15830D01*
X541732Y16613D01*
X540948Y17215D01*
X540035Y17593D01*
X539055Y17722D01*
D02*
G37*
G36*
X589055Y7722D02*
X588075Y7593D01*
X587163Y7215D01*
X586379Y6613D01*
X585777Y5830D01*
X585399Y4917D01*
X585270Y3937D01*
X585399Y2957D01*
X585777Y2044D01*
X586379Y1261D01*
X587163Y659D01*
X588075Y281D01*
X589055Y152D01*
X590035Y281D01*
X590948Y659D01*
X591732Y1261D01*
X592333Y2044D01*
X592711Y2957D01*
X592840Y3937D01*
X592711Y4917D01*
X592333Y5830D01*
X591732Y6613D01*
X590948Y7215D01*
X590035Y7593D01*
X589055Y7722D01*
D02*
G37*
G36*
X579055D02*
X578076Y7593D01*
X577163Y7215D01*
X576379Y6613D01*
X575777Y5830D01*
X575399Y4917D01*
X575270Y3937D01*
X575399Y2957D01*
X575777Y2044D01*
X576379Y1261D01*
X577163Y659D01*
X578076Y281D01*
X579055Y152D01*
X580035Y281D01*
X580948Y659D01*
X581732Y1261D01*
X582333Y2044D01*
X582711Y2957D01*
X582840Y3937D01*
X582711Y4917D01*
X582333Y5830D01*
X581732Y6613D01*
X580948Y7215D01*
X580035Y7593D01*
X579055Y7722D01*
D02*
G37*
G36*
X569055D02*
X568076Y7593D01*
X567163Y7215D01*
X566379Y6613D01*
X565777Y5830D01*
X565399Y4917D01*
X565270Y3937D01*
X565399Y2957D01*
X565777Y2044D01*
X566379Y1261D01*
X567163Y659D01*
X568076Y281D01*
X569055Y152D01*
X570035Y281D01*
X570948Y659D01*
X571732Y1261D01*
X572333Y2044D01*
X572711Y2957D01*
X572840Y3937D01*
X572711Y4917D01*
X572333Y5830D01*
X571732Y6613D01*
X570948Y7215D01*
X570035Y7593D01*
X569055Y7722D01*
D02*
G37*
G36*
X559055D02*
X558076Y7593D01*
X557163Y7215D01*
X556379Y6613D01*
X555777Y5830D01*
X555399Y4917D01*
X555270Y3937D01*
X555399Y2957D01*
X555777Y2044D01*
X556379Y1261D01*
X557163Y659D01*
X558076Y281D01*
X559055Y152D01*
X560035Y281D01*
X560948Y659D01*
X561732Y1261D01*
X562333Y2044D01*
X562711Y2957D01*
X562840Y3937D01*
X562711Y4917D01*
X562333Y5830D01*
X561732Y6613D01*
X560948Y7215D01*
X560035Y7593D01*
X559055Y7722D01*
D02*
G37*
G36*
X539055D02*
X538075Y7593D01*
X537163Y7215D01*
X536379Y6613D01*
X535777Y5830D01*
X535399Y4917D01*
X535270Y3937D01*
X535399Y2957D01*
X535777Y2044D01*
X536379Y1261D01*
X537163Y659D01*
X538075Y281D01*
X539055Y152D01*
X540035Y281D01*
X540948Y659D01*
X541732Y1261D01*
X542333Y2044D01*
X542711Y2957D01*
X542840Y3937D01*
X542711Y4917D01*
X542333Y5830D01*
X541732Y6613D01*
X540948Y7215D01*
X540035Y7593D01*
X539055Y7722D01*
D02*
G37*
G36*
X310069Y18245D02*
X308374Y18112D01*
X306721Y17715D01*
X305151Y17064D01*
X303701Y16176D01*
X302409Y15072D01*
X301305Y13780D01*
X300416Y12330D01*
X299766Y10759D01*
X299369Y9106D01*
X299236Y7412D01*
X299369Y5717D01*
X299766Y4064D01*
X300416Y2493D01*
X301305Y1044D01*
X302409Y-249D01*
X303701Y-1353D01*
X305151Y-2241D01*
X306721Y-2891D01*
X308374Y-3288D01*
X310069Y-3422D01*
X311764Y-3288D01*
X313417Y-2891D01*
X314987Y-2241D01*
X316437Y-1353D01*
X317729Y-249D01*
X318833Y1044D01*
X319722Y2493D01*
X320372Y4064D01*
X320769Y5717D01*
X320902Y7412D01*
X320769Y9106D01*
X320372Y10759D01*
X319722Y12330D01*
X318833Y13780D01*
X317729Y15072D01*
X316437Y16176D01*
X314987Y17064D01*
X313417Y17715D01*
X311764Y18112D01*
X310069Y18245D01*
D02*
G37*
G36*
X71880D02*
X70185Y18112D01*
X68532Y17715D01*
X66962Y17064D01*
X65512Y16176D01*
X64220Y15072D01*
X63116Y13780D01*
X62227Y12330D01*
X61577Y10759D01*
X61180Y9106D01*
X61046Y7412D01*
X61180Y5717D01*
X61577Y4064D01*
X62227Y2493D01*
X63116Y1044D01*
X64220Y-249D01*
X65512Y-1353D01*
X66962Y-2241D01*
X68532Y-2891D01*
X70185Y-3288D01*
X71880Y-3422D01*
X73575Y-3288D01*
X75228Y-2891D01*
X76798Y-2241D01*
X78248Y-1353D01*
X79540Y-249D01*
X80644Y1044D01*
X81533Y2493D01*
X82183Y4064D01*
X82580Y5717D01*
X82713Y7412D01*
X82580Y9106D01*
X82183Y10759D01*
X81533Y12330D01*
X80644Y13780D01*
X79540Y15072D01*
X78248Y16176D01*
X76798Y17064D01*
X75228Y17715D01*
X73575Y18112D01*
X71880Y18245D01*
D02*
G37*
G36*
X651545Y18088D02*
X649851Y17954D01*
X648198Y17558D01*
X646627Y16907D01*
X645178Y16019D01*
X643885Y14915D01*
X642781Y13622D01*
X641893Y12173D01*
X641242Y10602D01*
X640845Y8949D01*
X640712Y7254D01*
X640845Y5560D01*
X641242Y3907D01*
X641893Y2336D01*
X642781Y887D01*
X643885Y-406D01*
X645178Y-1510D01*
X646627Y-2398D01*
X648198Y-3049D01*
X649851Y-3446D01*
X651545Y-3579D01*
X653240Y-3446D01*
X654893Y-3049D01*
X656463Y-2398D01*
X657913Y-1510D01*
X659206Y-406D01*
X660310Y887D01*
X661198Y2336D01*
X661848Y3907D01*
X662245Y5560D01*
X662379Y7254D01*
X662245Y8949D01*
X661848Y10602D01*
X661198Y12173D01*
X660310Y13622D01*
X659206Y14915D01*
X657913Y16019D01*
X656463Y16907D01*
X654893Y17558D01*
X653240Y17954D01*
X651545Y18088D01*
D02*
G37*
G36*
X413356D02*
X411662Y17954D01*
X410009Y17558D01*
X408438Y16907D01*
X406989Y16019D01*
X405696Y14915D01*
X404592Y13622D01*
X403704Y12173D01*
X403053Y10602D01*
X402656Y8949D01*
X402523Y7254D01*
X402656Y5560D01*
X403053Y3907D01*
X403704Y2336D01*
X404592Y887D01*
X405696Y-406D01*
X406989Y-1510D01*
X408438Y-2398D01*
X410009Y-3049D01*
X411662Y-3446D01*
X413356Y-3579D01*
X415051Y-3446D01*
X416704Y-3049D01*
X418274Y-2398D01*
X419724Y-1510D01*
X421017Y-406D01*
X422121Y887D01*
X423009Y2336D01*
X423660Y3907D01*
X424056Y5560D01*
X424190Y7254D01*
X424056Y8949D01*
X423660Y10602D01*
X423009Y12173D01*
X422121Y13622D01*
X421017Y14915D01*
X419724Y16019D01*
X418274Y16907D01*
X416704Y17558D01*
X415051Y17954D01*
X413356Y18088D01*
D02*
G37*
G36*
X615158Y-7227D02*
X614533Y-7351D01*
X614004Y-7705D01*
X613650Y-8234D01*
X613526Y-8858D01*
X613650Y-9483D01*
X614004Y-10012D01*
X614533Y-10365D01*
X615158Y-10490D01*
X615782Y-10365D01*
X616311Y-10012D01*
X616665Y-9483D01*
X616789Y-8858D01*
X616665Y-8234D01*
X616311Y-7705D01*
X615782Y-7351D01*
X615158Y-7227D01*
D02*
G37*
G36*
X47244D02*
X46620Y-7351D01*
X46091Y-7705D01*
X45737Y-8234D01*
X45613Y-8858D01*
X45737Y-9483D01*
X46091Y-10012D01*
X46620Y-10365D01*
X47244Y-10490D01*
X47868Y-10365D01*
X48398Y-10012D01*
X48751Y-9483D01*
X48875Y-8858D01*
X48751Y-8234D01*
X48398Y-7705D01*
X47868Y-7351D01*
X47244Y-7227D01*
D02*
G37*
G36*
X40354D02*
X39730Y-7351D01*
X39201Y-7705D01*
X38847Y-8234D01*
X38723Y-8858D01*
X38847Y-9483D01*
X39201Y-10012D01*
X39730Y-10365D01*
X40354Y-10490D01*
X40979Y-10365D01*
X41508Y-10012D01*
X41862Y-9483D01*
X41986Y-8858D01*
X41862Y-8234D01*
X41508Y-7705D01*
X40979Y-7351D01*
X40354Y-7227D01*
D02*
G37*
G36*
X33465D02*
X32840Y-7351D01*
X32311Y-7705D01*
X31957Y-8234D01*
X31833Y-8858D01*
X31957Y-9483D01*
X32311Y-10012D01*
X32840Y-10365D01*
X33465Y-10490D01*
X34089Y-10365D01*
X34618Y-10012D01*
X34972Y-9483D01*
X35096Y-8858D01*
X34972Y-8234D01*
X34618Y-7705D01*
X34089Y-7351D01*
X33465Y-7227D01*
D02*
G37*
G36*
X26495Y-7360D02*
X25871Y-7484D01*
X25342Y-7838D01*
X24988Y-8367D01*
X24864Y-8991D01*
X24988Y-9616D01*
X25342Y-10145D01*
X25871Y-10498D01*
X26495Y-10623D01*
X27120Y-10498D01*
X27649Y-10145D01*
X28002Y-9616D01*
X28127Y-8991D01*
X28002Y-8367D01*
X27649Y-7838D01*
X27120Y-7484D01*
X26495Y-7360D01*
D02*
G37*
G36*
X685039Y13341D02*
X682952Y13177D01*
X680917Y12688D01*
X678983Y11887D01*
X677198Y10793D01*
X675606Y9434D01*
X674246Y7842D01*
X673152Y6057D01*
X672351Y4123D01*
X671863Y2087D01*
X671698Y0D01*
X671863Y-2087D01*
X672351Y-4123D01*
X673152Y-6057D01*
X674246Y-7842D01*
X675606Y-9434D01*
X677198Y-10793D01*
X678983Y-11887D01*
X680917Y-12688D01*
X682952Y-13177D01*
X685039Y-13341D01*
X687126Y-13177D01*
X689162Y-12688D01*
X691096Y-11887D01*
X692881Y-10793D01*
X694473Y-9434D01*
X695833Y-7842D01*
X696926Y-6057D01*
X697728Y-4123D01*
X698216Y-2087D01*
X698381Y0D01*
X698216Y2087D01*
X697728Y4123D01*
X696926Y6057D01*
X695833Y7842D01*
X694473Y9434D01*
X692881Y10793D01*
X691096Y11887D01*
X689162Y12688D01*
X687126Y13177D01*
X685039Y13341D01*
D02*
G37*
G36*
X0D02*
X-2087Y13177D01*
X-4123Y12688D01*
X-6057Y11887D01*
X-7842Y10793D01*
X-9434Y9434D01*
X-10793Y7842D01*
X-11887Y6057D01*
X-12688Y4123D01*
X-13177Y2087D01*
X-13341Y0D01*
X-13177Y-2087D01*
X-12688Y-4123D01*
X-11887Y-6057D01*
X-10793Y-7842D01*
X-9434Y-9434D01*
X-7842Y-10793D01*
X-6057Y-11887D01*
X-4123Y-12688D01*
X-2087Y-13177D01*
X0Y-13341D01*
X2087Y-13177D01*
X4123Y-12688D01*
X6057Y-11887D01*
X7842Y-10793D01*
X9434Y-9434D01*
X10793Y-7842D01*
X11887Y-6057D01*
X12688Y-4123D01*
X13177Y-2087D01*
X13341Y0D01*
X13177Y2087D01*
X12688Y4123D01*
X11887Y6057D01*
X10793Y7842D01*
X9434Y9434D01*
X7842Y10793D01*
X6057Y11887D01*
X4123Y12688D01*
X2087Y13177D01*
X0Y13341D01*
D02*
G37*
G36*
X640640Y-15621D02*
X639744Y-15799D01*
X638984Y-16307D01*
X638477Y-17066D01*
X638299Y-17962D01*
X638477Y-18858D01*
X638984Y-19618D01*
X639744Y-20125D01*
X640640Y-20303D01*
X641536Y-20125D01*
X642295Y-19618D01*
X642803Y-18858D01*
X642981Y-17962D01*
X642803Y-17066D01*
X642295Y-16307D01*
X641536Y-15799D01*
X640640Y-15621D01*
D02*
G37*
G36*
X658465Y-20268D02*
X657840Y-20392D01*
X657311Y-20746D01*
X656957Y-21275D01*
X656833Y-21899D01*
X656957Y-22524D01*
X657311Y-23053D01*
X657840Y-23406D01*
X658465Y-23531D01*
X659089Y-23406D01*
X659618Y-23053D01*
X659972Y-22524D01*
X660096Y-21899D01*
X659972Y-21275D01*
X659618Y-20746D01*
X659089Y-20392D01*
X658465Y-20268D01*
D02*
G37*
G36*
X625000D02*
X624376Y-20392D01*
X623846Y-20746D01*
X623493Y-21275D01*
X623369Y-21899D01*
X623493Y-22524D01*
X623846Y-23053D01*
X624376Y-23406D01*
X625000Y-23531D01*
X625624Y-23406D01*
X626154Y-23053D01*
X626507Y-22524D01*
X626631Y-21899D01*
X626507Y-21275D01*
X626154Y-20746D01*
X625624Y-20392D01*
X625000Y-20268D01*
D02*
G37*
G36*
X658465Y-28142D02*
X657840Y-28266D01*
X657311Y-28620D01*
X656957Y-29149D01*
X656833Y-29773D01*
X656957Y-30397D01*
X657311Y-30927D01*
X657840Y-31280D01*
X658465Y-31405D01*
X659089Y-31280D01*
X659618Y-30927D01*
X659972Y-30397D01*
X660096Y-29773D01*
X659972Y-29149D01*
X659618Y-28620D01*
X659089Y-28266D01*
X658465Y-28142D01*
D02*
G37*
G36*
X625000D02*
X624376Y-28266D01*
X623846Y-28620D01*
X623493Y-29149D01*
X623369Y-29773D01*
X623493Y-30397D01*
X623846Y-30927D01*
X624376Y-31280D01*
X625000Y-31405D01*
X625624Y-31280D01*
X626154Y-30927D01*
X626507Y-30397D01*
X626631Y-29773D01*
X626507Y-29149D01*
X626154Y-28620D01*
X625624Y-28266D01*
X625000Y-28142D01*
D02*
G37*
G36*
X640640Y-31369D02*
X639744Y-31547D01*
X638984Y-32055D01*
X638477Y-32814D01*
X638299Y-33710D01*
X638477Y-34606D01*
X638984Y-35366D01*
X639744Y-35873D01*
X640640Y-36051D01*
X641536Y-35873D01*
X642295Y-35366D01*
X642803Y-34606D01*
X642981Y-33710D01*
X642803Y-32814D01*
X642295Y-32055D01*
X641536Y-31547D01*
X640640Y-31369D01*
D02*
G37*
G36*
X658465Y-36016D02*
X657840Y-36140D01*
X657311Y-36494D01*
X656957Y-37023D01*
X656833Y-37647D01*
X656957Y-38271D01*
X657311Y-38801D01*
X657840Y-39154D01*
X658465Y-39279D01*
X659089Y-39154D01*
X659618Y-38801D01*
X659972Y-38271D01*
X660096Y-37647D01*
X659972Y-37023D01*
X659618Y-36494D01*
X659089Y-36140D01*
X658465Y-36016D01*
D02*
G37*
G36*
X625000Y-46449D02*
X624376Y-46573D01*
X623846Y-46927D01*
X623493Y-47456D01*
X623369Y-48080D01*
X623493Y-48705D01*
X623846Y-49234D01*
X624376Y-49588D01*
X625000Y-49712D01*
X625624Y-49588D01*
X626154Y-49234D01*
X626507Y-48705D01*
X626631Y-48080D01*
X626507Y-47456D01*
X626154Y-46927D01*
X625624Y-46573D01*
X625000Y-46449D01*
D02*
G37*
G36*
X65945Y-48417D02*
X65321Y-48542D01*
X64791Y-48895D01*
X64438Y-49424D01*
X64314Y-50049D01*
X64438Y-50673D01*
X64791Y-51202D01*
X65321Y-51556D01*
X65945Y-51680D01*
X66569Y-51556D01*
X67098Y-51202D01*
X67452Y-50673D01*
X67576Y-50049D01*
X67452Y-49424D01*
X67098Y-48895D01*
X66569Y-48542D01*
X65945Y-48417D01*
D02*
G37*
G36*
X82785Y-51645D02*
X81890Y-51823D01*
X81130Y-52330D01*
X80623Y-53090D01*
X80444Y-53986D01*
X80623Y-54882D01*
X81130Y-55641D01*
X81890Y-56149D01*
X82785Y-56327D01*
X83681Y-56149D01*
X84441Y-55641D01*
X84948Y-54882D01*
X85127Y-53986D01*
X84948Y-53090D01*
X84441Y-52330D01*
X83681Y-51823D01*
X82785Y-51645D01*
D02*
G37*
G36*
X99410Y-56292D02*
X98785Y-56416D01*
X98256Y-56769D01*
X97902Y-57299D01*
X97778Y-57923D01*
X97902Y-58547D01*
X98256Y-59076D01*
X98785Y-59430D01*
X99410Y-59554D01*
X100034Y-59430D01*
X100563Y-59076D01*
X100917Y-58547D01*
X101041Y-57923D01*
X100917Y-57299D01*
X100563Y-56769D01*
X100034Y-56416D01*
X99410Y-56292D01*
D02*
G37*
G36*
X65945D02*
X65321Y-56416D01*
X64791Y-56769D01*
X64438Y-57299D01*
X64314Y-57923D01*
X64438Y-58547D01*
X64791Y-59076D01*
X65321Y-59430D01*
X65945Y-59554D01*
X66569Y-59430D01*
X67098Y-59076D01*
X67452Y-58547D01*
X67576Y-57923D01*
X67452Y-57299D01*
X67098Y-56769D01*
X66569Y-56416D01*
X65945Y-56292D01*
D02*
G37*
G36*
X-23622Y-58408D02*
X-24246Y-58532D01*
X-24776Y-58886D01*
X-25129Y-59415D01*
X-25253Y-60039D01*
X-25129Y-60664D01*
X-24776Y-61193D01*
X-24667Y-61266D01*
Y-61766D01*
X-24776Y-61839D01*
X-25129Y-62368D01*
X-25253Y-62992D01*
X-25129Y-63616D01*
X-24776Y-64146D01*
X-24246Y-64499D01*
X-23622Y-64623D01*
X-22998Y-64499D01*
X-22468Y-64146D01*
X-22115Y-63616D01*
X-21991Y-62992D01*
X-22115Y-62368D01*
X-22468Y-61839D01*
X-22578Y-61766D01*
Y-61266D01*
X-22468Y-61193D01*
X-22115Y-60664D01*
X-21991Y-60039D01*
X-22115Y-59415D01*
X-22468Y-58886D01*
X-22998Y-58532D01*
X-23622Y-58408D01*
D02*
G37*
G36*
X651557Y-62675D02*
X650932Y-62799D01*
X650403Y-63153D01*
X650049Y-63682D01*
X649925Y-64306D01*
X650049Y-64931D01*
X650403Y-65460D01*
X650932Y-65813D01*
X651557Y-65938D01*
X652181Y-65813D01*
X652710Y-65460D01*
X653064Y-64931D01*
X653188Y-64306D01*
X653064Y-63682D01*
X652710Y-63153D01*
X652181Y-62799D01*
X651557Y-62675D01*
D02*
G37*
G36*
X99410Y-64166D02*
X98785Y-64290D01*
X98256Y-64643D01*
X97902Y-65173D01*
X97778Y-65797D01*
X97902Y-66421D01*
X98256Y-66950D01*
X98785Y-67304D01*
X99410Y-67428D01*
X100034Y-67304D01*
X100563Y-66950D01*
X100917Y-66421D01*
X101041Y-65797D01*
X100917Y-65173D01*
X100563Y-64643D01*
X100034Y-64290D01*
X99410Y-64166D01*
D02*
G37*
G36*
X65945D02*
X65321Y-64290D01*
X64791Y-64643D01*
X64438Y-65173D01*
X64314Y-65797D01*
X64438Y-66421D01*
X64791Y-66950D01*
X65321Y-67304D01*
X65945Y-67428D01*
X66569Y-67304D01*
X67098Y-66950D01*
X67452Y-66421D01*
X67576Y-65797D01*
X67452Y-65173D01*
X67098Y-64643D01*
X66569Y-64290D01*
X65945Y-64166D01*
D02*
G37*
G36*
X-23622Y-65298D02*
X-24246Y-65422D01*
X-24776Y-65776D01*
X-25129Y-66305D01*
X-25253Y-66929D01*
X-25129Y-67553D01*
X-24776Y-68083D01*
X-24246Y-68436D01*
X-23622Y-68560D01*
X-22998Y-68436D01*
X-22468Y-68083D01*
X-22115Y-67553D01*
X-21991Y-66929D01*
X-22115Y-66305D01*
X-22468Y-65776D01*
X-22998Y-65422D01*
X-23622Y-65298D01*
D02*
G37*
G36*
X574016Y-68841D02*
X573391Y-68965D01*
X572862Y-69319D01*
X572742Y-69499D01*
X572140D01*
X572020Y-69319D01*
X571490Y-68965D01*
X570866Y-68841D01*
X570242Y-68965D01*
X569713Y-69319D01*
X569359Y-69848D01*
X569235Y-70472D01*
X569359Y-71097D01*
X569599Y-71457D01*
X569359Y-71817D01*
X569235Y-72441D01*
X569359Y-73065D01*
X569599Y-73425D01*
X569359Y-73785D01*
X569235Y-74410D01*
X569359Y-75034D01*
X569713Y-75563D01*
X570242Y-75917D01*
X570866Y-76041D01*
X571490Y-75917D01*
X572020Y-75563D01*
X572140Y-75383D01*
X572742D01*
X572862Y-75563D01*
X573391Y-75917D01*
X574016Y-76041D01*
X574640Y-75917D01*
X575169Y-75563D01*
X575523Y-75034D01*
X575647Y-74410D01*
X575523Y-73785D01*
X575282Y-73425D01*
X575523Y-73065D01*
X575647Y-72441D01*
X575523Y-71817D01*
X575282Y-71457D01*
X575523Y-71097D01*
X575647Y-70472D01*
X575523Y-69848D01*
X575169Y-69319D01*
X574640Y-68965D01*
X574016Y-68841D01*
D02*
G37*
G36*
X82785Y-67393D02*
X81890Y-67571D01*
X81130Y-68079D01*
X80623Y-68838D01*
X80444Y-69734D01*
X80623Y-70630D01*
X81130Y-71389D01*
X81890Y-71897D01*
X82785Y-72075D01*
X83681Y-71897D01*
X84441Y-71389D01*
X84948Y-70630D01*
X85127Y-69734D01*
X84948Y-68838D01*
X84441Y-68079D01*
X83681Y-67571D01*
X82785Y-67393D01*
D02*
G37*
G36*
X-23622Y-69235D02*
X-24246Y-69359D01*
X-24776Y-69713D01*
X-25129Y-70242D01*
X-25253Y-70866D01*
X-25129Y-71490D01*
X-24776Y-72020D01*
X-24246Y-72373D01*
X-23622Y-72497D01*
X-22998Y-72373D01*
X-22468Y-72020D01*
X-22115Y-71490D01*
X-21991Y-70866D01*
X-22115Y-70242D01*
X-22468Y-69713D01*
X-22998Y-69359D01*
X-23622Y-69235D01*
D02*
G37*
G36*
X131890Y-71055D02*
X131265Y-71179D01*
X130736Y-71533D01*
X130383Y-72062D01*
X130258Y-72687D01*
X130383Y-73311D01*
X130736Y-73840D01*
X131265Y-74194D01*
X131890Y-74318D01*
X132514Y-74194D01*
X133043Y-73840D01*
X133397Y-73311D01*
X133521Y-72687D01*
X133397Y-72062D01*
X133043Y-71533D01*
X132514Y-71179D01*
X131890Y-71055D01*
D02*
G37*
G36*
X104528Y-90544D02*
X103903Y-90668D01*
X103374Y-91021D01*
X103020Y-91550D01*
X102896Y-92175D01*
X103020Y-92799D01*
X103374Y-93328D01*
X103903Y-93682D01*
X104528Y-93806D01*
X105152Y-93682D01*
X105681Y-93328D01*
X106035Y-92799D01*
X106159Y-92175D01*
X106035Y-91550D01*
X105681Y-91021D01*
X105152Y-90668D01*
X104528Y-90544D01*
D02*
G37*
G36*
X-23622Y-100731D02*
X-24246Y-100855D01*
X-24776Y-101209D01*
X-25129Y-101738D01*
X-25253Y-102362D01*
X-25129Y-102987D01*
X-24776Y-103516D01*
X-24246Y-103869D01*
X-23622Y-103994D01*
X-22998Y-103869D01*
X-22468Y-103516D01*
X-22115Y-102987D01*
X-21991Y-102362D01*
X-22115Y-101738D01*
X-22468Y-101209D01*
X-22998Y-100855D01*
X-23622Y-100731D01*
D02*
G37*
G36*
X310069Y-84117D02*
X308374Y-84250D01*
X306721Y-84647D01*
X305151Y-85298D01*
X303701Y-86186D01*
X302409Y-87290D01*
X301305Y-88583D01*
X300416Y-90032D01*
X299766Y-91603D01*
X299369Y-93256D01*
X299236Y-94950D01*
X299369Y-96645D01*
X299766Y-98298D01*
X300416Y-99869D01*
X301305Y-101318D01*
X302409Y-102611D01*
X303701Y-103715D01*
X305151Y-104603D01*
X306721Y-105254D01*
X308374Y-105650D01*
X310069Y-105784D01*
X311764Y-105650D01*
X313417Y-105254D01*
X314987Y-104603D01*
X316437Y-103715D01*
X317729Y-102611D01*
X318833Y-101318D01*
X319722Y-99869D01*
X320372Y-98298D01*
X320769Y-96645D01*
X320902Y-94950D01*
X320769Y-93256D01*
X320372Y-91603D01*
X319722Y-90032D01*
X318833Y-88583D01*
X317729Y-87290D01*
X316437Y-86186D01*
X314987Y-85298D01*
X313417Y-84647D01*
X311764Y-84250D01*
X310069Y-84117D01*
D02*
G37*
G36*
X71880D02*
X70185Y-84250D01*
X68532Y-84647D01*
X66962Y-85298D01*
X65512Y-86186D01*
X64220Y-87290D01*
X63116Y-88583D01*
X62227Y-90032D01*
X61577Y-91603D01*
X61180Y-93256D01*
X61046Y-94950D01*
X61180Y-96645D01*
X61577Y-98298D01*
X62227Y-99869D01*
X63116Y-101318D01*
X64220Y-102611D01*
X65512Y-103715D01*
X66962Y-104603D01*
X68532Y-105254D01*
X70185Y-105650D01*
X71880Y-105784D01*
X73575Y-105650D01*
X75228Y-105254D01*
X76798Y-104603D01*
X78248Y-103715D01*
X79540Y-102611D01*
X80644Y-101318D01*
X81533Y-99869D01*
X82183Y-98298D01*
X82580Y-96645D01*
X82713Y-94950D01*
X82580Y-93256D01*
X82183Y-91603D01*
X81533Y-90032D01*
X80644Y-88583D01*
X79540Y-87290D01*
X78248Y-86186D01*
X76798Y-85298D01*
X75228Y-84647D01*
X73575Y-84250D01*
X71880Y-84117D01*
D02*
G37*
G36*
X512795Y-102583D02*
X512171Y-102707D01*
X511642Y-103061D01*
X511288Y-103590D01*
X511164Y-104214D01*
X511288Y-104839D01*
X511642Y-105368D01*
X512171Y-105721D01*
X512795Y-105845D01*
X513420Y-105721D01*
X513949Y-105368D01*
X514302Y-104839D01*
X514427Y-104214D01*
X514302Y-103590D01*
X513949Y-103061D01*
X513420Y-102707D01*
X512795Y-102583D01*
D02*
G37*
G36*
X651545Y-84274D02*
X649851Y-84408D01*
X648198Y-84805D01*
X646627Y-85455D01*
X645178Y-86343D01*
X643885Y-87448D01*
X642781Y-88740D01*
X641893Y-90190D01*
X641242Y-91760D01*
X640845Y-93413D01*
X640712Y-95108D01*
X640845Y-96803D01*
X641242Y-98456D01*
X641893Y-100026D01*
X642781Y-101476D01*
X643885Y-102768D01*
X645178Y-103872D01*
X646627Y-104760D01*
X648198Y-105411D01*
X649851Y-105808D01*
X651545Y-105941D01*
X653240Y-105808D01*
X654893Y-105411D01*
X656463Y-104760D01*
X657913Y-103872D01*
X659206Y-102768D01*
X660310Y-101476D01*
X661198Y-100026D01*
X661848Y-98456D01*
X662245Y-96803D01*
X662379Y-95108D01*
X662245Y-93413D01*
X661848Y-91760D01*
X661198Y-90190D01*
X660310Y-88740D01*
X659206Y-87448D01*
X657913Y-86343D01*
X656463Y-85455D01*
X654893Y-84805D01*
X653240Y-84408D01*
X651545Y-84274D01*
D02*
G37*
G36*
X413356D02*
X411662Y-84408D01*
X410009Y-84805D01*
X408438Y-85455D01*
X406989Y-86343D01*
X405696Y-87448D01*
X404592Y-88740D01*
X403704Y-90190D01*
X403053Y-91760D01*
X402656Y-93413D01*
X402523Y-95108D01*
X402656Y-96803D01*
X403053Y-98456D01*
X403704Y-100026D01*
X404592Y-101476D01*
X405696Y-102768D01*
X406989Y-103872D01*
X408438Y-104760D01*
X410009Y-105411D01*
X411662Y-105808D01*
X413356Y-105941D01*
X415051Y-105808D01*
X416704Y-105411D01*
X418274Y-104760D01*
X419724Y-103872D01*
X421017Y-102768D01*
X422121Y-101476D01*
X423009Y-100026D01*
X423660Y-98456D01*
X424056Y-96803D01*
X424190Y-95108D01*
X424056Y-93413D01*
X423660Y-91760D01*
X423009Y-90190D01*
X422121Y-88740D01*
X421017Y-87448D01*
X419724Y-86343D01*
X418274Y-85455D01*
X416704Y-84805D01*
X415051Y-84408D01*
X413356Y-84274D01*
D02*
G37*
G36*
X269685Y-104520D02*
X269061Y-104644D01*
X268531Y-104998D01*
X268178Y-105527D01*
X268054Y-106151D01*
X268178Y-106775D01*
X268531Y-107305D01*
X269061Y-107658D01*
X269685Y-107782D01*
X270309Y-107658D01*
X270839Y-107305D01*
X271192Y-106775D01*
X271316Y-106151D01*
X271192Y-105527D01*
X270839Y-104998D01*
X270309Y-104644D01*
X269685Y-104520D01*
D02*
G37*
G36*
X-23622Y-104668D02*
X-24246Y-104792D01*
X-24776Y-105146D01*
X-25129Y-105675D01*
X-25253Y-106299D01*
X-25129Y-106923D01*
X-24776Y-107453D01*
X-24246Y-107806D01*
X-23622Y-107931D01*
X-22998Y-107806D01*
X-22468Y-107453D01*
X-22115Y-106923D01*
X-21991Y-106299D01*
X-22115Y-105675D01*
X-22468Y-105146D01*
X-22998Y-104792D01*
X-23622Y-104668D01*
D02*
G37*
G36*
X99347Y-108605D02*
X98722Y-108729D01*
X98193Y-109083D01*
X97839Y-109612D01*
X97715Y-110236D01*
X97362Y-110589D01*
X97284Y-110573D01*
X96659Y-110698D01*
X96130Y-111051D01*
X95776Y-111580D01*
X95652Y-112205D01*
X95776Y-112829D01*
X96130Y-113358D01*
X96659Y-113712D01*
X97284Y-113836D01*
X97908Y-113712D01*
X98437Y-113358D01*
X98791Y-112829D01*
X98855Y-112504D01*
X99372Y-112167D01*
X99605Y-112219D01*
X99673Y-112312D01*
X99776Y-112829D01*
X100130Y-113358D01*
X100659Y-113712D01*
X101284Y-113836D01*
X101908Y-113712D01*
X102437Y-113358D01*
X102791Y-112829D01*
X102915Y-112205D01*
X102791Y-111580D01*
X102437Y-111051D01*
X101908Y-110698D01*
X101415Y-110600D01*
X101126Y-110359D01*
X100956Y-110129D01*
X100854Y-109612D01*
X100500Y-109083D01*
X99971Y-108729D01*
X99347Y-108605D01*
D02*
G37*
G36*
X244094Y-107473D02*
X243470Y-107597D01*
X242941Y-107950D01*
X242587Y-108480D01*
X242463Y-109104D01*
X242587Y-109728D01*
X242941Y-110257D01*
X243470Y-110611D01*
X244094Y-110735D01*
X244719Y-110611D01*
X245248Y-110257D01*
X245602Y-109728D01*
X245726Y-109104D01*
X245602Y-108480D01*
X245248Y-107950D01*
X244719Y-107597D01*
X244094Y-107473D01*
D02*
G37*
G36*
X-23622Y-108605D02*
X-24246Y-108729D01*
X-24776Y-109083D01*
X-25129Y-109612D01*
X-25253Y-110236D01*
X-25129Y-110861D01*
X-24776Y-111390D01*
X-24246Y-111743D01*
X-23622Y-111868D01*
X-22998Y-111743D01*
X-22468Y-111390D01*
X-22115Y-110861D01*
X-21991Y-110236D01*
X-22115Y-109612D01*
X-22468Y-109083D01*
X-22998Y-108729D01*
X-23622Y-108605D01*
D02*
G37*
G36*
X354724Y-112148D02*
X354100Y-112272D01*
X353740Y-112513D01*
X353380Y-112272D01*
X352756Y-112148D01*
X352132Y-112272D01*
X351772Y-112513D01*
X351412Y-112272D01*
X350787Y-112148D01*
X350163Y-112272D01*
X349634Y-112626D01*
X349280Y-113155D01*
X349156Y-113779D01*
X349280Y-114404D01*
X349634Y-114933D01*
X349814Y-115054D01*
Y-115655D01*
X349634Y-115776D01*
X349280Y-116305D01*
X349156Y-116929D01*
X349280Y-117553D01*
X349634Y-118083D01*
X350163Y-118436D01*
X350787Y-118561D01*
X351412Y-118436D01*
X351772Y-118196D01*
X352132Y-118436D01*
X352756Y-118561D01*
X353380Y-118436D01*
X353740Y-118196D01*
X354100Y-118436D01*
X354724Y-118561D01*
X355349Y-118436D01*
X355878Y-118083D01*
X356232Y-117553D01*
X356356Y-116929D01*
X356232Y-116305D01*
X355878Y-115776D01*
X355697Y-115655D01*
Y-115054D01*
X355878Y-114933D01*
X356232Y-114404D01*
X356356Y-113779D01*
X356232Y-113155D01*
X355878Y-112626D01*
X355349Y-112272D01*
X354724Y-112148D01*
D02*
G37*
G36*
X107346Y-108605D02*
X106722Y-108729D01*
X106193Y-109083D01*
X105839Y-109612D01*
X105734Y-110141D01*
X105518Y-110433D01*
X105492Y-110459D01*
X105275Y-110588D01*
X104722Y-110698D01*
X104193Y-111051D01*
X103839Y-111580D01*
X103715Y-112205D01*
X103839Y-112829D01*
X104193Y-113358D01*
X104722Y-113712D01*
X105347Y-113836D01*
X105971Y-113712D01*
X106500Y-113358D01*
X106854Y-112829D01*
X106959Y-112300D01*
X107077Y-112140D01*
X107490Y-112080D01*
X107710Y-112129D01*
X107712Y-112132D01*
X107789Y-112289D01*
X107902Y-112861D01*
X108256Y-113390D01*
X108785Y-113743D01*
X109409Y-113868D01*
X110034Y-113743D01*
X110563Y-113390D01*
X110917Y-112861D01*
X111041Y-112236D01*
X110917Y-111612D01*
X110563Y-111083D01*
X110034Y-110729D01*
X109414Y-110606D01*
X109279Y-110576D01*
X109044Y-110340D01*
X108967Y-110183D01*
X108854Y-109612D01*
X108500Y-109083D01*
X107971Y-108729D01*
X107346Y-108605D01*
D02*
G37*
G36*
X309016Y-112355D02*
X308391Y-112479D01*
X307862Y-112832D01*
X307509Y-113362D01*
X307384Y-113986D01*
X307509Y-114610D01*
X307862Y-115139D01*
X308391Y-115493D01*
X309016Y-115617D01*
X309640Y-115493D01*
X310169Y-115139D01*
X310523Y-114610D01*
X310647Y-113986D01*
X310523Y-113362D01*
X310169Y-112832D01*
X309640Y-112479D01*
X309016Y-112355D01*
D02*
G37*
G36*
X483268Y-112394D02*
X482643Y-112518D01*
X482114Y-112872D01*
X481761Y-113401D01*
X481636Y-114025D01*
X481761Y-114649D01*
X482114Y-115179D01*
X482643Y-115532D01*
X483268Y-115656D01*
X483892Y-115532D01*
X484421Y-115179D01*
X484775Y-114649D01*
X484899Y-114025D01*
X484775Y-113401D01*
X484421Y-112872D01*
X483892Y-112518D01*
X483268Y-112394D01*
D02*
G37*
G36*
X487205Y-112425D02*
X486580Y-112549D01*
X486051Y-112903D01*
X485698Y-113432D01*
X485573Y-114057D01*
X485698Y-114681D01*
X486051Y-115210D01*
X486580Y-115564D01*
X487205Y-115688D01*
X487829Y-115564D01*
X488358Y-115210D01*
X488712Y-114681D01*
X488836Y-114057D01*
X488712Y-113432D01*
X488358Y-112903D01*
X487829Y-112549D01*
X487205Y-112425D01*
D02*
G37*
G36*
X-23622Y-112542D02*
X-24246Y-112666D01*
X-24776Y-113020D01*
X-25129Y-113549D01*
X-25253Y-114173D01*
X-25129Y-114797D01*
X-24776Y-115327D01*
X-24246Y-115680D01*
X-23622Y-115805D01*
X-22998Y-115680D01*
X-22468Y-115327D01*
X-22115Y-114797D01*
X-21991Y-114173D01*
X-22115Y-113549D01*
X-22468Y-113020D01*
X-22998Y-112666D01*
X-23622Y-112542D01*
D02*
G37*
G36*
X492319Y-113339D02*
X491695Y-113463D01*
X491166Y-113816D01*
X490812Y-114346D01*
X490688Y-114970D01*
X490812Y-115594D01*
X491166Y-116124D01*
X491695Y-116477D01*
X492319Y-116601D01*
X492944Y-116477D01*
X493473Y-116124D01*
X493827Y-115594D01*
X493951Y-114970D01*
X493827Y-114346D01*
X493473Y-113816D01*
X492944Y-113463D01*
X492319Y-113339D01*
D02*
G37*
G36*
X193898Y-113378D02*
X193273Y-113502D01*
X192744Y-113856D01*
X192391Y-114385D01*
X192266Y-115009D01*
X192391Y-115634D01*
X192744Y-116163D01*
X193273Y-116517D01*
X193898Y-116641D01*
X194522Y-116517D01*
X195051Y-116163D01*
X195405Y-115634D01*
X195529Y-115009D01*
X195405Y-114385D01*
X195051Y-113856D01*
X194522Y-113502D01*
X193898Y-113378D01*
D02*
G37*
G36*
X463551Y-114394D02*
X462927Y-114518D01*
X462398Y-114872D01*
X462044Y-115401D01*
X461920Y-116025D01*
X462044Y-116649D01*
X462398Y-117179D01*
X462927Y-117532D01*
X463551Y-117657D01*
X464176Y-117532D01*
X464705Y-117179D01*
X465058Y-116649D01*
X465182Y-116025D01*
X465058Y-115401D01*
X464705Y-114872D01*
X464176Y-114518D01*
X463551Y-114394D01*
D02*
G37*
G36*
X456742Y-114412D02*
X456118Y-114536D01*
X455589Y-114889D01*
X455235Y-115419D01*
X455111Y-116043D01*
X455235Y-116667D01*
X455589Y-117197D01*
X456118Y-117550D01*
X456742Y-117674D01*
X457366Y-117550D01*
X457896Y-117197D01*
X458249Y-116667D01*
X458373Y-116043D01*
X458249Y-115419D01*
X457896Y-114889D01*
X457366Y-114536D01*
X456742Y-114412D01*
D02*
G37*
G36*
X533878Y-116085D02*
X533254Y-116209D01*
X532725Y-116563D01*
X532371Y-117092D01*
X532247Y-117716D01*
X532371Y-118340D01*
X532725Y-118870D01*
X533254Y-119223D01*
X533878Y-119348D01*
X534502Y-119223D01*
X535032Y-118870D01*
X535385Y-118340D01*
X535509Y-117716D01*
X535385Y-117092D01*
X535032Y-116563D01*
X534502Y-116209D01*
X533878Y-116085D01*
D02*
G37*
G36*
X314961Y-117315D02*
X314336Y-117439D01*
X313807Y-117793D01*
X313454Y-118322D01*
X313329Y-118947D01*
X313454Y-119571D01*
X313807Y-120100D01*
X314336Y-120454D01*
X314961Y-120578D01*
X315585Y-120454D01*
X316114Y-120100D01*
X316468Y-119571D01*
X316592Y-118947D01*
X316468Y-118322D01*
X316114Y-117793D01*
X315585Y-117439D01*
X314961Y-117315D01*
D02*
G37*
G36*
X193898Y-118299D02*
X193273Y-118423D01*
X192744Y-118777D01*
X192391Y-119306D01*
X192266Y-119931D01*
X192391Y-120555D01*
X192744Y-121084D01*
X193273Y-121438D01*
X193898Y-121562D01*
X194522Y-121438D01*
X195051Y-121084D01*
X195405Y-120555D01*
X195529Y-119931D01*
X195405Y-119306D01*
X195051Y-118777D01*
X194522Y-118423D01*
X193898Y-118299D01*
D02*
G37*
G36*
X70866Y-120416D02*
X70242Y-120540D01*
X69713Y-120894D01*
X69359Y-121423D01*
X69235Y-122047D01*
X69359Y-122671D01*
X69713Y-123201D01*
X70242Y-123554D01*
X70866Y-123679D01*
X71490Y-123554D01*
X72020Y-123201D01*
X72373Y-122671D01*
X72497Y-122047D01*
X72373Y-121423D01*
X72020Y-120894D01*
X71490Y-120540D01*
X70866Y-120416D01*
D02*
G37*
G36*
X176115Y-116326D02*
X168609D01*
Y-123831D01*
X176115D01*
Y-116326D01*
D02*
G37*
G36*
X152362Y-116294D02*
X151383Y-116423D01*
X150470Y-116801D01*
X149686Y-117402D01*
X149084Y-118186D01*
X148706Y-119099D01*
X148577Y-120079D01*
X148706Y-121058D01*
X149084Y-121971D01*
X149686Y-122755D01*
X150470Y-123357D01*
X151383Y-123735D01*
X152362Y-123864D01*
X153342Y-123735D01*
X154255Y-123357D01*
X155039Y-122755D01*
X155640Y-121971D01*
X156018Y-121058D01*
X156147Y-120079D01*
X156018Y-119099D01*
X155640Y-118186D01*
X155039Y-117402D01*
X154255Y-116801D01*
X153342Y-116423D01*
X152362Y-116294D01*
D02*
G37*
G36*
X142362D02*
X141383Y-116423D01*
X140470Y-116801D01*
X139686Y-117402D01*
X139084Y-118186D01*
X138706Y-119099D01*
X138577Y-120079D01*
X138706Y-121058D01*
X139084Y-121971D01*
X139686Y-122755D01*
X140470Y-123357D01*
X141383Y-123735D01*
X142362Y-123864D01*
X143342Y-123735D01*
X144255Y-123357D01*
X145039Y-122755D01*
X145640Y-121971D01*
X146018Y-121058D01*
X146147Y-120079D01*
X146018Y-119099D01*
X145640Y-118186D01*
X145039Y-117402D01*
X144255Y-116801D01*
X143342Y-116423D01*
X142362Y-116294D01*
D02*
G37*
G36*
X267323Y-121252D02*
X266699Y-121376D01*
X266169Y-121730D01*
X265816Y-122259D01*
X265691Y-122883D01*
X265816Y-123508D01*
X266169Y-124037D01*
X266699Y-124391D01*
X267323Y-124515D01*
X267947Y-124391D01*
X268476Y-124037D01*
X268830Y-123508D01*
X268954Y-122883D01*
X268830Y-122259D01*
X268476Y-121730D01*
X267947Y-121376D01*
X267323Y-121252D01*
D02*
G37*
G36*
X412339Y-122174D02*
X411715Y-122298D01*
X411186Y-122652D01*
X410832Y-123181D01*
X410708Y-123805D01*
X410832Y-124430D01*
X411186Y-124959D01*
X411715Y-125313D01*
X412339Y-125437D01*
X412964Y-125313D01*
X413493Y-124959D01*
X413847Y-124430D01*
X413971Y-123805D01*
X413847Y-123181D01*
X413493Y-122652D01*
X412964Y-122298D01*
X412339Y-122174D01*
D02*
G37*
G36*
X309055Y-122236D02*
X308431Y-122361D01*
X307902Y-122714D01*
X307548Y-123243D01*
X307424Y-123868D01*
X307548Y-124492D01*
X307902Y-125021D01*
X308431Y-125375D01*
X309055Y-125499D01*
X309679Y-125375D01*
X310209Y-125021D01*
X310562Y-124492D01*
X310686Y-123868D01*
X310562Y-123243D01*
X310209Y-122714D01*
X309679Y-122361D01*
X309055Y-122236D01*
D02*
G37*
G36*
X117126Y-118290D02*
X116502Y-118414D01*
X115972Y-118768D01*
X115619Y-119297D01*
X115495Y-119921D01*
X115619Y-120546D01*
X115972Y-121075D01*
X116502Y-121428D01*
X117126Y-121553D01*
X117276Y-122013D01*
X117223Y-122292D01*
X117030Y-122434D01*
X116502Y-122539D01*
X115972Y-122893D01*
X115619Y-123422D01*
X115495Y-124047D01*
X115619Y-124671D01*
X115972Y-125200D01*
X116502Y-125554D01*
X117126Y-125678D01*
X117750Y-125554D01*
X118280Y-125200D01*
X118633Y-124671D01*
X118743Y-124118D01*
X118871Y-123901D01*
X118898Y-123875D01*
X119190Y-123659D01*
X119719Y-123554D01*
X120248Y-123200D01*
X120602Y-122671D01*
X120726Y-122047D01*
X120602Y-121422D01*
X120248Y-120893D01*
X119719Y-120539D01*
X119095Y-120415D01*
X119082Y-120418D01*
X118729Y-120064D01*
X118757Y-119921D01*
X118633Y-119297D01*
X118280Y-118768D01*
X117750Y-118414D01*
X117126Y-118290D01*
D02*
G37*
G36*
X597244Y-126321D02*
X596620Y-126446D01*
X596260Y-126686D01*
X595900Y-126446D01*
X595276Y-126321D01*
X594651Y-126446D01*
X594291Y-126686D01*
X593931Y-126446D01*
X593307Y-126321D01*
X592683Y-126446D01*
X592154Y-126799D01*
X591800Y-127329D01*
X591676Y-127953D01*
X591800Y-128577D01*
X592154Y-129106D01*
X592334Y-129227D01*
Y-129828D01*
X592154Y-129949D01*
X591800Y-130478D01*
X591676Y-131102D01*
X591800Y-131727D01*
X592154Y-132256D01*
X592683Y-132609D01*
X593307Y-132734D01*
X593931Y-132609D01*
X594291Y-132369D01*
X594651Y-132609D01*
X595276Y-132734D01*
X595900Y-132609D01*
X596260Y-132369D01*
X596620Y-132609D01*
X597244Y-132734D01*
X597868Y-132609D01*
X598398Y-132256D01*
X598751Y-131727D01*
X598876Y-131102D01*
X598751Y-130478D01*
X598398Y-129949D01*
X598217Y-129828D01*
Y-129227D01*
X598398Y-129106D01*
X598751Y-128577D01*
X598876Y-127953D01*
X598751Y-127329D01*
X598398Y-126799D01*
X597868Y-126446D01*
X597244Y-126321D01*
D02*
G37*
G36*
X576132Y-122159D02*
X575196Y-122346D01*
X574402Y-122876D01*
X573872Y-123670D01*
X573685Y-124606D01*
X573872Y-125543D01*
X574402Y-126337D01*
X575196Y-126867D01*
X576132Y-127053D01*
X577069Y-126867D01*
X577863Y-126337D01*
X578393Y-125543D01*
X578579Y-124606D01*
X578393Y-123670D01*
X577863Y-122876D01*
X577069Y-122346D01*
X576132Y-122159D01*
D02*
G37*
G36*
X330709Y-118841D02*
X330084Y-118965D01*
X329555Y-119319D01*
X329202Y-119848D01*
X329077Y-120473D01*
X329202Y-121097D01*
X329555Y-121626D01*
X329664Y-121699D01*
Y-122199D01*
X329555Y-122272D01*
X329202Y-122801D01*
X329077Y-123425D01*
X329202Y-124049D01*
X329555Y-124579D01*
X329664Y-124652D01*
Y-125152D01*
X329555Y-125224D01*
X329202Y-125754D01*
X329077Y-126378D01*
X329202Y-127002D01*
X329555Y-127532D01*
X330084Y-127885D01*
X330709Y-128009D01*
X331333Y-127885D01*
X331862Y-127532D01*
X332216Y-127002D01*
X332340Y-126378D01*
X332216Y-125754D01*
X331862Y-125224D01*
X331753Y-125152D01*
Y-124652D01*
X331862Y-124579D01*
X332216Y-124049D01*
X332340Y-123425D01*
X332216Y-122801D01*
X331862Y-122272D01*
X331753Y-122199D01*
Y-121699D01*
X331862Y-121626D01*
X332216Y-121097D01*
X332340Y-120473D01*
X332216Y-119848D01*
X331862Y-119319D01*
X331333Y-118965D01*
X330709Y-118841D01*
D02*
G37*
G36*
X534400Y-125337D02*
X533776Y-125461D01*
X533247Y-125815D01*
X532893Y-126344D01*
X532769Y-126969D01*
X532893Y-127593D01*
X533247Y-128122D01*
X533776Y-128476D01*
X534400Y-128600D01*
X535024Y-128476D01*
X535554Y-128122D01*
X535907Y-127593D01*
X536031Y-126969D01*
X535907Y-126344D01*
X535554Y-125815D01*
X535024Y-125461D01*
X534400Y-125337D01*
D02*
G37*
G36*
X375984Y-118447D02*
X375360Y-118572D01*
X374831Y-118925D01*
X374477Y-119454D01*
X374353Y-120079D01*
X374477Y-120703D01*
X374831Y-121232D01*
X375264Y-121522D01*
X375252Y-121916D01*
X375211Y-122042D01*
X374908Y-122103D01*
X374379Y-122456D01*
X374025Y-122985D01*
X373901Y-123610D01*
X374025Y-124234D01*
X374379Y-124763D01*
X374908Y-125117D01*
X375016Y-125138D01*
Y-125648D01*
X374966Y-125658D01*
X374437Y-126012D01*
X374083Y-126541D01*
X373959Y-127165D01*
X374083Y-127790D01*
X374437Y-128319D01*
X374966Y-128673D01*
X375590Y-128797D01*
X376215Y-128673D01*
X376744Y-128319D01*
X377098Y-127790D01*
X377222Y-127165D01*
X377098Y-126541D01*
X376744Y-126012D01*
X376215Y-125658D01*
X376107Y-125637D01*
Y-125127D01*
X376156Y-125117D01*
X376686Y-124763D01*
X377039Y-124234D01*
X377164Y-123610D01*
X377039Y-122985D01*
X376686Y-122456D01*
X376252Y-122167D01*
X376264Y-121772D01*
X376305Y-121646D01*
X376608Y-121586D01*
X377138Y-121232D01*
X377491Y-120703D01*
X377616Y-120079D01*
X377491Y-119454D01*
X377138Y-118925D01*
X376608Y-118572D01*
X375984Y-118447D01*
D02*
G37*
G36*
X309016Y-127028D02*
X308391Y-127152D01*
X307862Y-127506D01*
X307509Y-128035D01*
X307384Y-128659D01*
X307509Y-129283D01*
X307862Y-129813D01*
X308391Y-130166D01*
X309016Y-130290D01*
X309640Y-130166D01*
X310169Y-129813D01*
X310523Y-129283D01*
X310647Y-128659D01*
X310523Y-128035D01*
X310169Y-127506D01*
X309640Y-127152D01*
X309016Y-127028D01*
D02*
G37*
G36*
X524606Y-124205D02*
X523982Y-124329D01*
X523453Y-124683D01*
X523099Y-125212D01*
X522975Y-125836D01*
X523099Y-126461D01*
X523453Y-126990D01*
X523500Y-127022D01*
Y-127522D01*
X523404Y-127586D01*
X523050Y-128115D01*
X522926Y-128740D01*
X523050Y-129364D01*
X523404Y-129893D01*
X523933Y-130247D01*
X524557Y-130371D01*
X525181Y-130247D01*
X525711Y-129893D01*
X526064Y-129364D01*
X526188Y-128740D01*
X526064Y-128115D01*
X525711Y-127586D01*
X525663Y-127554D01*
Y-127054D01*
X525760Y-126990D01*
X526114Y-126461D01*
X526238Y-125836D01*
X526114Y-125212D01*
X525760Y-124683D01*
X525231Y-124329D01*
X524606Y-124205D01*
D02*
G37*
G36*
X237008Y-127945D02*
X236384Y-128069D01*
X235854Y-128423D01*
X235501Y-128952D01*
X235377Y-129576D01*
X235501Y-130201D01*
X235854Y-130730D01*
X236384Y-131084D01*
X237008Y-131208D01*
X237632Y-131084D01*
X238161Y-130730D01*
X238515Y-130201D01*
X238639Y-129576D01*
X238515Y-128952D01*
X238161Y-128423D01*
X237632Y-128069D01*
X237008Y-127945D01*
D02*
G37*
G36*
X267286Y-129066D02*
X266662Y-129190D01*
X266133Y-129543D01*
X265779Y-130073D01*
X265655Y-130697D01*
X265779Y-131321D01*
X266133Y-131851D01*
X266662Y-132204D01*
X267286Y-132328D01*
X267911Y-132204D01*
X268440Y-131851D01*
X268794Y-131321D01*
X268918Y-130697D01*
X268794Y-130073D01*
X268440Y-129543D01*
X267911Y-129190D01*
X267286Y-129066D01*
D02*
G37*
G36*
X240945Y-131833D02*
X240321Y-131957D01*
X239791Y-132311D01*
X239438Y-132840D01*
X239428Y-132888D01*
X238918D01*
X238909Y-132840D01*
X238555Y-132311D01*
X238026Y-131957D01*
X237402Y-131833D01*
X236777Y-131957D01*
X236248Y-132311D01*
X235894Y-132840D01*
X235770Y-133465D01*
X235894Y-134089D01*
X236248Y-134618D01*
X236777Y-134972D01*
X237402Y-135096D01*
X238026Y-134972D01*
X238555Y-134618D01*
X238909Y-134089D01*
X238918Y-134041D01*
X239428D01*
X239438Y-134089D01*
X239791Y-134618D01*
X240321Y-134972D01*
X240945Y-135096D01*
X241569Y-134972D01*
X242098Y-134618D01*
X242452Y-134089D01*
X242576Y-133465D01*
X242452Y-132840D01*
X242098Y-132311D01*
X241569Y-131957D01*
X240945Y-131833D01*
D02*
G37*
G36*
X505905Y-130110D02*
X505281Y-130235D01*
X504752Y-130588D01*
X504398Y-131117D01*
X504274Y-131742D01*
X504398Y-132366D01*
X504752Y-132895D01*
X505281Y-133249D01*
X505905Y-133373D01*
X506530Y-133249D01*
X507059Y-132895D01*
X507413Y-132366D01*
X507537Y-131742D01*
X507413Y-131117D01*
X507059Y-130588D01*
X506530Y-130235D01*
X505905Y-130110D01*
D02*
G37*
G36*
X117126Y-126415D02*
X116502Y-126540D01*
X115972Y-126893D01*
X115619Y-127422D01*
X115495Y-128047D01*
X115619Y-128671D01*
X115972Y-129200D01*
X116502Y-129554D01*
X117030Y-129659D01*
X117114Y-129721D01*
X117190Y-129903D01*
X117190Y-130193D01*
X117114Y-130373D01*
X117031Y-130435D01*
X116502Y-130540D01*
X115972Y-130894D01*
X115619Y-131423D01*
X115495Y-132047D01*
X115619Y-132671D01*
X115972Y-133201D01*
X116502Y-133554D01*
X117126Y-133679D01*
X117750Y-133554D01*
X118280Y-133201D01*
X118633Y-132671D01*
X118743Y-132118D01*
X118870Y-131903D01*
X118899Y-131874D01*
X119190Y-131659D01*
X119719Y-131554D01*
X120248Y-131200D01*
X120602Y-130671D01*
X120726Y-130047D01*
X120602Y-129422D01*
X120248Y-128893D01*
X119719Y-128540D01*
X119190Y-128434D01*
X118898Y-128218D01*
X118871Y-128192D01*
X118743Y-127975D01*
X118633Y-127422D01*
X118280Y-126893D01*
X117750Y-126540D01*
X117126Y-126415D01*
D02*
G37*
G36*
X475295Y-131981D02*
X474671Y-132105D01*
X474142Y-132458D01*
X473788Y-132987D01*
X473664Y-133612D01*
X473788Y-134236D01*
X474142Y-134765D01*
X474671Y-135119D01*
X475295Y-135243D01*
X475920Y-135119D01*
X476449Y-134765D01*
X476802Y-134236D01*
X476927Y-133612D01*
X476802Y-132987D01*
X476449Y-132458D01*
X475920Y-132105D01*
X475295Y-131981D01*
D02*
G37*
G36*
X405512Y-134980D02*
X404887Y-135104D01*
X404358Y-135458D01*
X404005Y-135987D01*
X403881Y-136611D01*
X404005Y-137235D01*
X404358Y-137765D01*
X404887Y-138118D01*
X405512Y-138242D01*
X406136Y-138118D01*
X406665Y-137765D01*
X407019Y-137235D01*
X407143Y-136611D01*
X407019Y-135987D01*
X406665Y-135458D01*
X406136Y-135104D01*
X405512Y-134980D01*
D02*
G37*
G36*
X399618Y-135196D02*
X398994Y-135320D01*
X398464Y-135674D01*
X398111Y-136203D01*
X397987Y-136828D01*
X398111Y-137452D01*
X398464Y-137981D01*
X398994Y-138335D01*
X399618Y-138459D01*
X400242Y-138335D01*
X400772Y-137981D01*
X401125Y-137452D01*
X401249Y-136828D01*
X401125Y-136203D01*
X400772Y-135674D01*
X400242Y-135320D01*
X399618Y-135196D01*
D02*
G37*
G36*
X469521Y-135983D02*
X468896Y-136108D01*
X468367Y-136461D01*
X468013Y-136990D01*
X467889Y-137615D01*
X468013Y-138239D01*
X468367Y-138768D01*
X468896Y-139122D01*
X469521Y-139246D01*
X470145Y-139122D01*
X470674Y-138768D01*
X471028Y-138239D01*
X471152Y-137615D01*
X471028Y-136990D01*
X470674Y-136461D01*
X470145Y-136108D01*
X469521Y-135983D01*
D02*
G37*
G36*
X379134Y-136164D02*
X378510Y-136288D01*
X377980Y-136642D01*
X377627Y-137171D01*
X377502Y-137795D01*
X377627Y-138420D01*
X377980Y-138949D01*
X378510Y-139302D01*
X379134Y-139427D01*
X379758Y-139302D01*
X380287Y-138949D01*
X380641Y-138420D01*
X380765Y-137795D01*
X380641Y-137171D01*
X380287Y-136642D01*
X379758Y-136288D01*
X379134Y-136164D01*
D02*
G37*
G36*
X109409Y-138480D02*
X108785Y-138604D01*
X108256Y-138958D01*
X107902Y-139487D01*
X107822Y-139890D01*
X107288Y-140015D01*
X106978Y-139795D01*
X106917Y-139487D01*
X106563Y-138958D01*
X106034Y-138604D01*
X105409Y-138480D01*
X104785Y-138604D01*
X104256Y-138958D01*
X103902Y-139487D01*
X103778Y-140111D01*
X103902Y-140735D01*
X104256Y-141265D01*
X104785Y-141618D01*
X105409Y-141742D01*
X105841Y-142049D01*
X105902Y-142357D01*
X106256Y-142886D01*
X106785Y-143239D01*
X107409Y-143364D01*
X108034Y-143239D01*
X108563Y-142886D01*
X108917Y-142357D01*
X109041Y-141732D01*
X109326Y-141726D01*
X109409Y-141742D01*
X110034Y-141618D01*
X110563Y-141265D01*
X110917Y-140735D01*
X111041Y-140111D01*
X110917Y-139487D01*
X110563Y-138958D01*
X110034Y-138604D01*
X109409Y-138480D01*
D02*
G37*
G36*
X101409D02*
X100785Y-138604D01*
X100256Y-138958D01*
X99902Y-139487D01*
X99822Y-139890D01*
X99288Y-140015D01*
X98978Y-139795D01*
X98917Y-139487D01*
X98563Y-138958D01*
X98034Y-138604D01*
X97409Y-138480D01*
X96785Y-138604D01*
X96256Y-138958D01*
X95902Y-139487D01*
X95778Y-140111D01*
X95902Y-140735D01*
X96256Y-141265D01*
X96785Y-141618D01*
X97409Y-141742D01*
X97841Y-142049D01*
X97902Y-142357D01*
X98256Y-142886D01*
X98785Y-143239D01*
X99410Y-143364D01*
X100034Y-143239D01*
X100563Y-142886D01*
X100917Y-142357D01*
X101041Y-141732D01*
X101326Y-141726D01*
X101409Y-141742D01*
X102034Y-141618D01*
X102563Y-141265D01*
X102917Y-140735D01*
X103041Y-140111D01*
X102917Y-139487D01*
X102563Y-138958D01*
X102034Y-138604D01*
X101409Y-138480D01*
D02*
G37*
G36*
X87254Y-137997D02*
X86630Y-138121D01*
X86101Y-138475D01*
X85747Y-139004D01*
X85623Y-139629D01*
X85747Y-140253D01*
X86101Y-140782D01*
X86630Y-141136D01*
X87254Y-141260D01*
X87879Y-141136D01*
X88115Y-140978D01*
X88413Y-141424D01*
X88943Y-141777D01*
X89567Y-141901D01*
X90191Y-141777D01*
X90720Y-141424D01*
X91074Y-140894D01*
X91198Y-140270D01*
X91074Y-139646D01*
X90720Y-139117D01*
X90191Y-138763D01*
X89567Y-138639D01*
X88943Y-138763D01*
X88706Y-138921D01*
X88408Y-138475D01*
X87879Y-138121D01*
X87254Y-137997D01*
D02*
G37*
G36*
X418898Y-142512D02*
X418273Y-142636D01*
X417808Y-142947D01*
X417609Y-142995D01*
X417162Y-142961D01*
X416730Y-142672D01*
X416106Y-142548D01*
X415481Y-142672D01*
X414952Y-143026D01*
X414598Y-143555D01*
X414474Y-144180D01*
X414598Y-144804D01*
X414952Y-145333D01*
X415481Y-145687D01*
X416106Y-145811D01*
X416730Y-145687D01*
X417195Y-145376D01*
X417394Y-145328D01*
X417841Y-145362D01*
X418273Y-145650D01*
X418898Y-145775D01*
X419522Y-145650D01*
X420051Y-145297D01*
X420405Y-144768D01*
X420529Y-144143D01*
X420405Y-143519D01*
X420051Y-142990D01*
X419522Y-142636D01*
X418898Y-142512D01*
D02*
G37*
G36*
X461319Y-142118D02*
X460695Y-142242D01*
X460165Y-142596D01*
X459812Y-143125D01*
X459688Y-143750D01*
X459812Y-144374D01*
X460165Y-144903D01*
X460695Y-145257D01*
X461319Y-145381D01*
X461943Y-145257D01*
X462472Y-144903D01*
X462826Y-144374D01*
X462950Y-143750D01*
X462826Y-143125D01*
X462472Y-142596D01*
X461943Y-142242D01*
X461319Y-142118D01*
D02*
G37*
G36*
X469291Y-142217D02*
X468667Y-142341D01*
X468138Y-142694D01*
X467784Y-143224D01*
X467660Y-143848D01*
X467784Y-144472D01*
X468138Y-145002D01*
X468667Y-145355D01*
X469291Y-145479D01*
X469916Y-145355D01*
X470445Y-145002D01*
X470798Y-144472D01*
X470923Y-143848D01*
X470798Y-143224D01*
X470445Y-142694D01*
X469916Y-142341D01*
X469291Y-142217D01*
D02*
G37*
G36*
X398568Y-143452D02*
X397944Y-143576D01*
X397415Y-143930D01*
X397061Y-144459D01*
X396937Y-145083D01*
X397061Y-145707D01*
X397415Y-146237D01*
X397944Y-146590D01*
X398568Y-146714D01*
X399193Y-146590D01*
X399722Y-146237D01*
X400075Y-145707D01*
X400200Y-145083D01*
X400075Y-144459D01*
X399722Y-143930D01*
X399193Y-143576D01*
X398568Y-143452D01*
D02*
G37*
G36*
X464328Y-144766D02*
X463704Y-144890D01*
X463175Y-145243D01*
X462821Y-145773D01*
X462697Y-146397D01*
X462821Y-147021D01*
X463175Y-147550D01*
X463704Y-147904D01*
X464328Y-148028D01*
X464953Y-147904D01*
X465482Y-147550D01*
X465836Y-147021D01*
X465960Y-146397D01*
X465836Y-145773D01*
X465482Y-145243D01*
X464953Y-144890D01*
X464328Y-144766D01*
D02*
G37*
G36*
X302362Y-152104D02*
X301174Y-152260D01*
X300068Y-152718D01*
X299117Y-153448D01*
X298388Y-154398D01*
X297929Y-155505D01*
X297773Y-156693D01*
X297929Y-157881D01*
X298388Y-158987D01*
X299117Y-159938D01*
X300068Y-160667D01*
X301174Y-161126D01*
X302362Y-161282D01*
X303550Y-161126D01*
X304657Y-160667D01*
X305607Y-159938D01*
X306337Y-158987D01*
X306795Y-157881D01*
X306951Y-156693D01*
X306795Y-155505D01*
X306337Y-154398D01*
X305607Y-153448D01*
X304657Y-152718D01*
X303550Y-152260D01*
X302362Y-152104D01*
D02*
G37*
G36*
X142520D02*
X141332Y-152260D01*
X140225Y-152718D01*
X139275Y-153448D01*
X138545Y-154398D01*
X138087Y-155505D01*
X137930Y-156693D01*
X138087Y-157881D01*
X138545Y-158987D01*
X139275Y-159938D01*
X140225Y-160667D01*
X141332Y-161126D01*
X142520Y-161282D01*
X143708Y-161126D01*
X144814Y-160667D01*
X145765Y-159938D01*
X146494Y-158987D01*
X146953Y-157881D01*
X147109Y-156693D01*
X146953Y-155505D01*
X146494Y-154398D01*
X145765Y-153448D01*
X144814Y-152718D01*
X143708Y-152260D01*
X142520Y-152104D01*
D02*
G37*
G36*
X-3728Y-152595D02*
X-13202D01*
Y-162069D01*
X-3728D01*
Y-152595D01*
D02*
G37*
G36*
X406528Y-156135D02*
X405903Y-156260D01*
X405374Y-156613D01*
X405020Y-157142D01*
X404896Y-157767D01*
X405020Y-158391D01*
X405374Y-158920D01*
X405783Y-159194D01*
X406004Y-159762D01*
X405973Y-159809D01*
X405849Y-160433D01*
X405973Y-161057D01*
X406327Y-161587D01*
X406436Y-161659D01*
Y-162159D01*
X406327Y-162232D01*
X406254Y-162341D01*
X405754D01*
X405681Y-162232D01*
X405152Y-161879D01*
X404528Y-161755D01*
X403903Y-161879D01*
X403374Y-162232D01*
X403020Y-162761D01*
X402896Y-163386D01*
X403020Y-164010D01*
X403374Y-164539D01*
X403903Y-164893D01*
X404528Y-165017D01*
X405152Y-164893D01*
X405681Y-164539D01*
X405754Y-164430D01*
X406254D01*
X406327Y-164539D01*
X406856Y-164893D01*
X407480Y-165017D01*
X408105Y-164893D01*
X408634Y-164539D01*
X408988Y-164010D01*
X409112Y-163386D01*
X408988Y-162761D01*
X408634Y-162232D01*
X408525Y-162159D01*
Y-161659D01*
X408634Y-161587D01*
X408988Y-161057D01*
X409112Y-160433D01*
X408988Y-159809D01*
X408634Y-159280D01*
X408225Y-159006D01*
X408003Y-158438D01*
X408035Y-158391D01*
X408159Y-157767D01*
X408035Y-157142D01*
X407681Y-156613D01*
X407152Y-156260D01*
X406528Y-156135D01*
D02*
G37*
G36*
X470285Y-158557D02*
X469550Y-158703D01*
X468927Y-159119D01*
X468511Y-159742D01*
X468365Y-160477D01*
X468511Y-161211D01*
X468927Y-161834D01*
X469550Y-162250D01*
X470285Y-162397D01*
X471019Y-162250D01*
X471642Y-161834D01*
X472058Y-161211D01*
X472204Y-160477D01*
X472058Y-159742D01*
X471642Y-159119D01*
X471019Y-158703D01*
X470285Y-158557D01*
D02*
G37*
G36*
X391545D02*
X390810Y-158703D01*
X390187Y-159119D01*
X389771Y-159742D01*
X389625Y-160477D01*
X389771Y-161211D01*
X390187Y-161834D01*
X390810Y-162250D01*
X391545Y-162397D01*
X392279Y-162250D01*
X392902Y-161834D01*
X393318Y-161211D01*
X393464Y-160477D01*
X393318Y-159742D01*
X392902Y-159119D01*
X392279Y-158703D01*
X391545Y-158557D01*
D02*
G37*
G36*
X533015Y-149026D02*
X531701Y-149155D01*
X530437Y-149539D01*
X529272Y-150162D01*
X528251Y-151000D01*
X527413Y-152021D01*
X526790Y-153185D01*
X526407Y-154449D01*
X526277Y-155764D01*
X526407Y-157079D01*
X526790Y-158343D01*
X527413Y-159507D01*
X528251Y-160529D01*
X529272Y-161366D01*
X530437Y-161989D01*
X531701Y-162373D01*
X533015Y-162502D01*
X534330Y-162373D01*
X535594Y-161989D01*
X536759Y-161366D01*
X537780Y-160529D01*
X538618Y-159507D01*
X539240Y-158343D01*
X539624Y-157079D01*
X539753Y-155764D01*
X539624Y-154449D01*
X539240Y-153185D01*
X538618Y-152021D01*
X537780Y-151000D01*
X536759Y-150162D01*
X535594Y-149539D01*
X534330Y-149155D01*
X533015Y-149026D01*
D02*
G37*
G36*
X336415D02*
X335101Y-149155D01*
X333837Y-149539D01*
X332672Y-150162D01*
X331651Y-151000D01*
X330813Y-152021D01*
X330190Y-153185D01*
X329807Y-154449D01*
X329677Y-155764D01*
X329807Y-157079D01*
X330190Y-158343D01*
X330813Y-159507D01*
X331651Y-160529D01*
X332672Y-161366D01*
X333837Y-161989D01*
X335101Y-162373D01*
X336415Y-162502D01*
X337730Y-162373D01*
X338994Y-161989D01*
X340159Y-161366D01*
X341180Y-160529D01*
X342018Y-159507D01*
X342640Y-158343D01*
X343024Y-157079D01*
X343153Y-155764D01*
X343024Y-154449D01*
X342640Y-153185D01*
X342018Y-152021D01*
X341180Y-151000D01*
X340159Y-150162D01*
X338994Y-149539D01*
X337730Y-149155D01*
X336415Y-149026D01*
D02*
G37*
G36*
X89567Y-164739D02*
X88943Y-164863D01*
X88762Y-164984D01*
X88321Y-165223D01*
X87792Y-164870D01*
X87167Y-164746D01*
X86543Y-164870D01*
X86014Y-165223D01*
X85660Y-165753D01*
X85536Y-166377D01*
X85660Y-167001D01*
X85835Y-167263D01*
X85917Y-167649D01*
X85707Y-167904D01*
X85409Y-168103D01*
X85055Y-168633D01*
X84931Y-169257D01*
X85055Y-169881D01*
X85409Y-170411D01*
X85938Y-170764D01*
X86562Y-170888D01*
X87186Y-170764D01*
X87716Y-170411D01*
X88069Y-169881D01*
X88194Y-169257D01*
X88069Y-168633D01*
X87894Y-168371D01*
X87813Y-167985D01*
X88013Y-167741D01*
X88414Y-167524D01*
X88943Y-167877D01*
X89567Y-168001D01*
X90192Y-167877D01*
X90721Y-167524D01*
X91074Y-166994D01*
X91199Y-166370D01*
X91074Y-165746D01*
X90721Y-165217D01*
X90192Y-164863D01*
X89567Y-164739D01*
D02*
G37*
G36*
X645669Y-155647D02*
X644176Y-155843D01*
X642784Y-156420D01*
X641589Y-157337D01*
X640672Y-158532D01*
X640095Y-159924D01*
X639899Y-161417D01*
X640095Y-162911D01*
X640672Y-164303D01*
X641589Y-165498D01*
X642784Y-166415D01*
X644176Y-166991D01*
X645669Y-167188D01*
X647163Y-166991D01*
X648555Y-166415D01*
X649750Y-165498D01*
X650667Y-164303D01*
X651243Y-162911D01*
X651440Y-161417D01*
X651243Y-159924D01*
X650667Y-158532D01*
X649750Y-157337D01*
X648555Y-156420D01*
X647163Y-155843D01*
X645669Y-155647D01*
D02*
G37*
G36*
X674409Y-154679D02*
X673095Y-154809D01*
X671831Y-155192D01*
X670666Y-155815D01*
X669645Y-156653D01*
X668807Y-157674D01*
X668184Y-158839D01*
X667801Y-160103D01*
X667671Y-161417D01*
X667801Y-162732D01*
X668184Y-163996D01*
X668807Y-165161D01*
X669645Y-166182D01*
X670666Y-167020D01*
X671831Y-167642D01*
X673095Y-168026D01*
X674409Y-168155D01*
X675724Y-168026D01*
X676988Y-167642D01*
X678153Y-167020D01*
X679174Y-166182D01*
X680012Y-165161D01*
X680634Y-163996D01*
X681018Y-162732D01*
X681147Y-161417D01*
X681018Y-160103D01*
X680634Y-158839D01*
X680012Y-157674D01*
X679174Y-156653D01*
X678153Y-155815D01*
X676988Y-155192D01*
X675724Y-154809D01*
X674409Y-154679D01*
D02*
G37*
G36*
X30512Y-168644D02*
X29888Y-168768D01*
X29358Y-169122D01*
X29005Y-169651D01*
X28881Y-170276D01*
X29005Y-170900D01*
X29358Y-171429D01*
X29888Y-171783D01*
X30512Y-171907D01*
X31136Y-171783D01*
X31665Y-171429D01*
X32019Y-170900D01*
X32143Y-170276D01*
X32019Y-169651D01*
X31665Y-169122D01*
X31136Y-168768D01*
X30512Y-168644D01*
D02*
G37*
G36*
X413440Y-173219D02*
X412815Y-173343D01*
X412286Y-173696D01*
X411787Y-173547D01*
X411667Y-173467D01*
X411043Y-173343D01*
X410418Y-173467D01*
X409889Y-173820D01*
X409536Y-174350D01*
X409411Y-174974D01*
X409536Y-175598D01*
X409889Y-176128D01*
X410418Y-176481D01*
X411043Y-176605D01*
X411667Y-176481D01*
X412196Y-176128D01*
X412696Y-176277D01*
X412815Y-176357D01*
X413440Y-176481D01*
X414064Y-176357D01*
X414593Y-176004D01*
X414947Y-175474D01*
X415071Y-174850D01*
X414947Y-174226D01*
X414593Y-173696D01*
X414064Y-173343D01*
X413440Y-173219D01*
D02*
G37*
G36*
X404823Y-173713D02*
X404199Y-173837D01*
X403911Y-174029D01*
X403543Y-174149D01*
X403176Y-174029D01*
X402888Y-173837D01*
X402264Y-173713D01*
X401640Y-173837D01*
X401110Y-174191D01*
X400757Y-174720D01*
X400632Y-175344D01*
X400757Y-175968D01*
X401110Y-176498D01*
X401640Y-176851D01*
X402264Y-176976D01*
X402888Y-176851D01*
X403176Y-176659D01*
X403543Y-176539D01*
X403911Y-176659D01*
X404199Y-176851D01*
X404823Y-176976D01*
X405447Y-176851D01*
X405976Y-176498D01*
X406330Y-175968D01*
X406454Y-175344D01*
X406330Y-174720D01*
X405976Y-174191D01*
X405447Y-173837D01*
X404823Y-173713D01*
D02*
G37*
G36*
X450850Y-172495D02*
X450225Y-172620D01*
X449696Y-172973D01*
X449342Y-173502D01*
X449218Y-174127D01*
X449342Y-174751D01*
X449696Y-175280D01*
X450225Y-175634D01*
X450850Y-175758D01*
X451474Y-175634D01*
X452003Y-175280D01*
X452357Y-174751D01*
X452481Y-174127D01*
X452357Y-173502D01*
X452003Y-172973D01*
X451474Y-172620D01*
X450850Y-172495D01*
D02*
G37*
G36*
X443898Y-173417D02*
X443273Y-173542D01*
X442744Y-173895D01*
X442390Y-174425D01*
X442266Y-175049D01*
X442390Y-175673D01*
X442744Y-176202D01*
X443273Y-176556D01*
X443898Y-176680D01*
X444522Y-176556D01*
X445051Y-176202D01*
X445405Y-175673D01*
X445529Y-175049D01*
X445405Y-174425D01*
X445051Y-173895D01*
X444522Y-173542D01*
X443898Y-173417D01*
D02*
G37*
G36*
X469390Y-173516D02*
X468765Y-173640D01*
X468236Y-173994D01*
X467883Y-174523D01*
X467758Y-175147D01*
X467883Y-175771D01*
X468236Y-176301D01*
X468765Y-176654D01*
X469390Y-176779D01*
X470014Y-176654D01*
X470543Y-176301D01*
X470897Y-175771D01*
X471021Y-175147D01*
X470897Y-174523D01*
X470543Y-173994D01*
X470014Y-173640D01*
X469390Y-173516D01*
D02*
G37*
G36*
X457283D02*
X456659Y-173640D01*
X456130Y-173994D01*
X455776Y-174523D01*
X455652Y-175147D01*
X455776Y-175771D01*
X456130Y-176301D01*
X456659Y-176654D01*
X457283Y-176779D01*
X457908Y-176654D01*
X458437Y-176301D01*
X458791Y-175771D01*
X458915Y-175147D01*
X458791Y-174523D01*
X458437Y-173994D01*
X457908Y-173640D01*
X457283Y-173516D01*
D02*
G37*
G36*
X417596Y-173565D02*
X416972Y-173690D01*
X416443Y-174043D01*
X416089Y-174573D01*
X415965Y-175197D01*
X416089Y-175821D01*
X416443Y-176350D01*
X416972Y-176704D01*
X417596Y-176828D01*
X418221Y-176704D01*
X418750Y-176350D01*
X419103Y-175821D01*
X419228Y-175197D01*
X419103Y-174573D01*
X418750Y-174043D01*
X418221Y-173690D01*
X417596Y-173565D01*
D02*
G37*
G36*
X86614D02*
X85990Y-173690D01*
X85461Y-174043D01*
X85107Y-174573D01*
X84983Y-175197D01*
X85107Y-175821D01*
X85461Y-176350D01*
X85990Y-176704D01*
X86614Y-176828D01*
X87239Y-176704D01*
X87768Y-176350D01*
X88121Y-175821D01*
X88245Y-175197D01*
X88121Y-174573D01*
X87768Y-174043D01*
X87239Y-173690D01*
X86614Y-173565D01*
D02*
G37*
G36*
X437697Y-173614D02*
X437073Y-173739D01*
X436543Y-174092D01*
X436190Y-174621D01*
X436065Y-175246D01*
X436190Y-175870D01*
X436543Y-176399D01*
X437073Y-176753D01*
X437697Y-176877D01*
X438321Y-176753D01*
X438850Y-176399D01*
X439204Y-175870D01*
X439328Y-175246D01*
X439204Y-174621D01*
X438850Y-174092D01*
X438321Y-173739D01*
X437697Y-173614D01*
D02*
G37*
G36*
X421596Y-173402D02*
X420972Y-173526D01*
X420443Y-173880D01*
X420089Y-174409D01*
X419965Y-175034D01*
X420089Y-175658D01*
X420443Y-176187D01*
X420972Y-176541D01*
X421596Y-176665D01*
X422221Y-176541D01*
X422750Y-176187D01*
X423057Y-176397D01*
X423059Y-176399D01*
X423588Y-176753D01*
X424213Y-176877D01*
X424837Y-176753D01*
X425366Y-176399D01*
X425439Y-176290D01*
X425939D01*
X426012Y-176399D01*
X426541Y-176753D01*
X427165Y-176877D01*
X427790Y-176753D01*
X428319Y-176399D01*
X428673Y-175870D01*
X428722Y-175624D01*
X429231D01*
X429300Y-175968D01*
X429654Y-176498D01*
X430183Y-176851D01*
X430807Y-176976D01*
X431431Y-176851D01*
X431961Y-176498D01*
X432065Y-176342D01*
X432666D01*
X432705Y-176399D01*
X433234Y-176753D01*
X433858Y-176877D01*
X434483Y-176753D01*
X435012Y-176399D01*
X435365Y-175870D01*
X435490Y-175246D01*
X435365Y-174621D01*
X435012Y-174092D01*
X434483Y-173739D01*
X433858Y-173614D01*
X433234Y-173739D01*
X432705Y-174092D01*
X432600Y-174248D01*
X431999D01*
X431961Y-174191D01*
X431431Y-173837D01*
X430807Y-173713D01*
X430183Y-173837D01*
X429654Y-174191D01*
X429300Y-174720D01*
X429251Y-174966D01*
X428741D01*
X428673Y-174621D01*
X428319Y-174092D01*
X427790Y-173739D01*
X427165Y-173614D01*
X426541Y-173739D01*
X426012Y-174092D01*
X425939Y-174201D01*
X425439D01*
X425366Y-174092D01*
X424837Y-173739D01*
X424213Y-173614D01*
X423588Y-173739D01*
X423059Y-174092D01*
X422751Y-173882D01*
X422750Y-173880D01*
X422221Y-173526D01*
X421596Y-173402D01*
D02*
G37*
G36*
X-23622Y-175534D02*
X-24246Y-175658D01*
X-24776Y-176012D01*
X-25129Y-176541D01*
X-25253Y-177165D01*
X-25129Y-177790D01*
X-24776Y-178319D01*
X-24246Y-178673D01*
X-23622Y-178797D01*
X-22998Y-178673D01*
X-22468Y-178319D01*
X-22115Y-177790D01*
X-21991Y-177165D01*
X-22115Y-176541D01*
X-22468Y-176012D01*
X-22998Y-175658D01*
X-23622Y-175534D01*
D02*
G37*
G36*
X74803Y-177503D02*
X74179Y-177627D01*
X73650Y-177980D01*
X73296Y-178510D01*
X73172Y-179134D01*
X73296Y-179758D01*
X73650Y-180287D01*
X74179Y-180641D01*
X74803Y-180765D01*
X75427Y-180641D01*
X75957Y-180287D01*
X76310Y-179758D01*
X76434Y-179134D01*
X76310Y-178510D01*
X75957Y-177980D01*
X75427Y-177627D01*
X74803Y-177503D01*
D02*
G37*
G36*
X63976D02*
X63352Y-177627D01*
X62823Y-177980D01*
X62469Y-178510D01*
X62345Y-179134D01*
X62469Y-179758D01*
X62823Y-180287D01*
X63352Y-180641D01*
X63976Y-180765D01*
X64601Y-180641D01*
X65130Y-180287D01*
X65484Y-179758D01*
X65608Y-179134D01*
X65484Y-178510D01*
X65130Y-177980D01*
X64601Y-177627D01*
X63976Y-177503D01*
D02*
G37*
G36*
X80709Y-178487D02*
X80084Y-178611D01*
X79555Y-178965D01*
X79202Y-179494D01*
X79077Y-180118D01*
X79202Y-180742D01*
X79555Y-181272D01*
X80084Y-181625D01*
X80709Y-181749D01*
X81333Y-181625D01*
X81862Y-181272D01*
X82216Y-180742D01*
X82340Y-180118D01*
X82216Y-179494D01*
X81862Y-178965D01*
X81333Y-178611D01*
X80709Y-178487D01*
D02*
G37*
G36*
X645669Y-172182D02*
X644176Y-172379D01*
X642784Y-172955D01*
X641589Y-173872D01*
X640672Y-175067D01*
X640095Y-176459D01*
X639899Y-177953D01*
X640095Y-179446D01*
X640672Y-180838D01*
X641589Y-182033D01*
X642784Y-182950D01*
X644176Y-183527D01*
X645669Y-183723D01*
X647163Y-183527D01*
X648555Y-182950D01*
X649750Y-182033D01*
X650667Y-180838D01*
X651243Y-179446D01*
X651440Y-177953D01*
X651243Y-176459D01*
X650667Y-175067D01*
X649750Y-173872D01*
X648555Y-172955D01*
X647163Y-172379D01*
X645669Y-172182D01*
D02*
G37*
G36*
X-23622Y-179471D02*
X-24246Y-179595D01*
X-24776Y-179949D01*
X-25129Y-180478D01*
X-25253Y-181102D01*
X-25129Y-181727D01*
X-24776Y-182256D01*
X-24667Y-182329D01*
Y-182829D01*
X-24776Y-182902D01*
X-25129Y-183431D01*
X-25253Y-184055D01*
X-25129Y-184679D01*
X-24776Y-185209D01*
X-24246Y-185562D01*
X-23622Y-185687D01*
X-22998Y-185562D01*
X-22468Y-185209D01*
X-22115Y-184679D01*
X-21991Y-184055D01*
X-22115Y-183431D01*
X-22468Y-182902D01*
X-22578Y-182829D01*
Y-182329D01*
X-22468Y-182256D01*
X-22115Y-181727D01*
X-21991Y-181102D01*
X-22115Y-180478D01*
X-22468Y-179949D01*
X-22998Y-179595D01*
X-23622Y-179471D01*
D02*
G37*
G36*
Y-186361D02*
X-24246Y-186485D01*
X-24776Y-186839D01*
X-25129Y-187368D01*
X-25253Y-187992D01*
X-25129Y-188616D01*
X-24776Y-189146D01*
X-24246Y-189499D01*
X-23622Y-189623D01*
X-22998Y-189499D01*
X-22468Y-189146D01*
X-22115Y-188616D01*
X-21991Y-187992D01*
X-22115Y-187368D01*
X-22468Y-186839D01*
X-22998Y-186485D01*
X-23622Y-186361D01*
D02*
G37*
G36*
X358661Y-192857D02*
X358037Y-192981D01*
X357508Y-193335D01*
X357154Y-193864D01*
X357030Y-194488D01*
X357154Y-195113D01*
X357508Y-195642D01*
X358037Y-195995D01*
X358661Y-196119D01*
X359286Y-195995D01*
X359815Y-195642D01*
X360169Y-195113D01*
X360293Y-194488D01*
X360169Y-193864D01*
X359815Y-193335D01*
X359286Y-192981D01*
X358661Y-192857D01*
D02*
G37*
G36*
X340904Y-192750D02*
X340170Y-192896D01*
X339547Y-193312D01*
X339131Y-193935D01*
X338984Y-194670D01*
X339131Y-195405D01*
X339547Y-196028D01*
X340170Y-196444D01*
X340904Y-196590D01*
X341639Y-196444D01*
X342262Y-196028D01*
X342678Y-195405D01*
X342824Y-194670D01*
X342678Y-193935D01*
X342262Y-193312D01*
X341639Y-192896D01*
X340904Y-192750D01*
D02*
G37*
G36*
X528395Y-192760D02*
X527661Y-192906D01*
X527038Y-193322D01*
X526622Y-193945D01*
X526475Y-194680D01*
X526622Y-195414D01*
X527038Y-196037D01*
X527661Y-196453D01*
X528395Y-196600D01*
X529130Y-196453D01*
X529753Y-196037D01*
X530169Y-195414D01*
X530315Y-194680D01*
X530169Y-193945D01*
X529753Y-193322D01*
X529130Y-192906D01*
X528395Y-192760D01*
D02*
G37*
G36*
X416835Y-194949D02*
X416210Y-195074D01*
X415681Y-195427D01*
X415328Y-195957D01*
X415203Y-196581D01*
X415328Y-197205D01*
X415681Y-197734D01*
X416210Y-198088D01*
X416835Y-198212D01*
X417459Y-198088D01*
X417988Y-197734D01*
X418342Y-197205D01*
X418466Y-196581D01*
X418342Y-195957D01*
X417988Y-195427D01*
X417459Y-195074D01*
X416835Y-194949D01*
D02*
G37*
G36*
X411811Y-195219D02*
X411187Y-195343D01*
X410658Y-195697D01*
X410304Y-196226D01*
X410180Y-196850D01*
X410304Y-197475D01*
X410658Y-198004D01*
X411187Y-198358D01*
X411811Y-198482D01*
X412435Y-198358D01*
X412965Y-198004D01*
X413318Y-197475D01*
X413442Y-196850D01*
X413318Y-196226D01*
X412965Y-195697D01*
X412435Y-195343D01*
X411811Y-195219D01*
D02*
G37*
G36*
X326966Y-193540D02*
X326342Y-193664D01*
X325813Y-194018D01*
X325459Y-194547D01*
X325335Y-195171D01*
X325459Y-195795D01*
X325813Y-196325D01*
X325580Y-196771D01*
X325461Y-196949D01*
X325337Y-197573D01*
X325461Y-198197D01*
X325815Y-198727D01*
X326344Y-199080D01*
X326969Y-199205D01*
X327593Y-199080D01*
X328122Y-198727D01*
X328476Y-198197D01*
X328600Y-197573D01*
X328476Y-196949D01*
X328122Y-196420D01*
X328355Y-195974D01*
X328474Y-195795D01*
X328598Y-195171D01*
X328474Y-194547D01*
X328120Y-194018D01*
X327591Y-193664D01*
X326966Y-193540D01*
D02*
G37*
G36*
X645669Y-188718D02*
X644176Y-188914D01*
X642784Y-189491D01*
X641589Y-190408D01*
X640672Y-191603D01*
X640095Y-192995D01*
X639899Y-194488D01*
X640095Y-195982D01*
X640672Y-197373D01*
X641589Y-198569D01*
X642784Y-199486D01*
X644176Y-200062D01*
X645669Y-200259D01*
X647163Y-200062D01*
X648555Y-199486D01*
X649750Y-198569D01*
X650667Y-197373D01*
X651243Y-195982D01*
X651440Y-194488D01*
X651243Y-192995D01*
X650667Y-191603D01*
X649750Y-190408D01*
X648555Y-189491D01*
X647163Y-188914D01*
X645669Y-188718D01*
D02*
G37*
G36*
X674409Y-187750D02*
X673095Y-187880D01*
X671831Y-188263D01*
X670666Y-188886D01*
X669645Y-189724D01*
X668807Y-190745D01*
X668184Y-191910D01*
X667801Y-193174D01*
X667671Y-194488D01*
X667801Y-195803D01*
X668184Y-197067D01*
X668807Y-198232D01*
X669645Y-199253D01*
X670666Y-200091D01*
X671831Y-200713D01*
X673095Y-201097D01*
X674409Y-201226D01*
X675724Y-201097D01*
X676988Y-200713D01*
X678153Y-200091D01*
X679174Y-199253D01*
X680012Y-198232D01*
X680634Y-197067D01*
X681018Y-195803D01*
X681147Y-194488D01*
X681018Y-193174D01*
X680634Y-191910D01*
X680012Y-190745D01*
X679174Y-189724D01*
X678153Y-188886D01*
X676988Y-188263D01*
X675724Y-187880D01*
X674409Y-187750D01*
D02*
G37*
G36*
X372016Y-199156D02*
X371392Y-199280D01*
X370862Y-199634D01*
X370509Y-200163D01*
X370384Y-200787D01*
X370509Y-201412D01*
X370862Y-201941D01*
X371392Y-202295D01*
X372016Y-202419D01*
X372640Y-202295D01*
X373169Y-201941D01*
X373523Y-201412D01*
X373647Y-200787D01*
X373523Y-200163D01*
X373169Y-199634D01*
X372640Y-199280D01*
X372016Y-199156D01*
D02*
G37*
G36*
X544291Y-194087D02*
X543667Y-194211D01*
X543138Y-194565D01*
X542784Y-195094D01*
X542660Y-195718D01*
X542784Y-196342D01*
X543025Y-196702D01*
X542784Y-197062D01*
X542660Y-197687D01*
X542784Y-198311D01*
X543025Y-198671D01*
X542784Y-199031D01*
X542660Y-199655D01*
X542784Y-200279D01*
X543025Y-200639D01*
X542784Y-200999D01*
X542660Y-201624D01*
X542784Y-202248D01*
X543138Y-202777D01*
X543667Y-203131D01*
X544291Y-203255D01*
X544916Y-203131D01*
X545445Y-202777D01*
X545798Y-202248D01*
X545923Y-201624D01*
X545798Y-200999D01*
X545558Y-200639D01*
X545798Y-200279D01*
X545923Y-199655D01*
X545798Y-199031D01*
X545558Y-198671D01*
X545798Y-198311D01*
X545923Y-197687D01*
X545798Y-197062D01*
X545558Y-196702D01*
X545798Y-196342D01*
X545923Y-195718D01*
X545798Y-195094D01*
X545445Y-194565D01*
X544916Y-194211D01*
X544291Y-194087D01*
D02*
G37*
G36*
X509842D02*
X509218Y-194211D01*
X508689Y-194565D01*
X508335Y-195094D01*
X508211Y-195718D01*
X508335Y-196342D01*
X508576Y-196702D01*
X508335Y-197062D01*
X508211Y-197687D01*
X508335Y-198311D01*
X508576Y-198671D01*
X508335Y-199031D01*
X508211Y-199655D01*
X508335Y-200279D01*
X508576Y-200639D01*
X508335Y-200999D01*
X508211Y-201624D01*
X508335Y-202248D01*
X508689Y-202777D01*
X509218Y-203131D01*
X509842Y-203255D01*
X510467Y-203131D01*
X510996Y-202777D01*
X511350Y-202248D01*
X511474Y-201624D01*
X511350Y-200999D01*
X511109Y-200639D01*
X511350Y-200279D01*
X511474Y-199655D01*
X511350Y-199031D01*
X511109Y-198671D01*
X511350Y-198311D01*
X511474Y-197687D01*
X511350Y-197062D01*
X511109Y-196702D01*
X511350Y-196342D01*
X511474Y-195718D01*
X511350Y-195094D01*
X510996Y-194565D01*
X510467Y-194211D01*
X509842Y-194087D01*
D02*
G37*
G36*
X366535Y-200731D02*
X365911Y-200855D01*
X365382Y-201209D01*
X365028Y-201738D01*
X364904Y-202362D01*
X365028Y-202987D01*
X365382Y-203516D01*
X365911Y-203869D01*
X366535Y-203994D01*
X367160Y-203869D01*
X367689Y-203516D01*
X368043Y-202987D01*
X368167Y-202362D01*
X368043Y-201738D01*
X367689Y-201209D01*
X367160Y-200855D01*
X366535Y-200731D01*
D02*
G37*
G36*
X361417Y-201518D02*
X360793Y-201642D01*
X360264Y-201996D01*
X359910Y-202525D01*
X359786Y-203150D01*
X359910Y-203774D01*
X360264Y-204303D01*
X360793Y-204657D01*
X361417Y-204781D01*
X362042Y-204657D01*
X362571Y-204303D01*
X362925Y-203774D01*
X363049Y-203150D01*
X362925Y-202525D01*
X362571Y-201996D01*
X362042Y-201642D01*
X361417Y-201518D01*
D02*
G37*
G36*
X379921Y-200109D02*
X379297Y-200233D01*
X378768Y-200587D01*
X378414Y-201116D01*
X378303Y-201675D01*
X378209Y-201843D01*
X378024Y-202028D01*
X377856Y-202122D01*
X377297Y-202233D01*
X376768Y-202587D01*
X376414Y-203116D01*
X376290Y-203740D01*
X376414Y-204364D01*
X376768Y-204894D01*
X377297Y-205247D01*
X377921Y-205371D01*
X378546Y-205247D01*
X379075Y-204894D01*
X379428Y-204364D01*
X379540Y-203805D01*
X379633Y-203637D01*
X379818Y-203452D01*
X379987Y-203359D01*
X380546Y-203247D01*
X381075Y-202894D01*
X381428Y-202364D01*
X381553Y-201740D01*
X381428Y-201116D01*
X381075Y-200587D01*
X380546Y-200233D01*
X379921Y-200109D01*
D02*
G37*
G36*
X658661Y-206636D02*
X658037Y-206761D01*
X657677Y-207001D01*
X657317Y-206761D01*
X656693Y-206636D01*
X656069Y-206761D01*
X655709Y-207001D01*
X655349Y-206761D01*
X654724Y-206636D01*
X654100Y-206761D01*
X653571Y-207114D01*
X653217Y-207643D01*
X653093Y-208268D01*
X653217Y-208892D01*
X653571Y-209421D01*
X653751Y-209542D01*
Y-210143D01*
X653571Y-210264D01*
X653217Y-210793D01*
X653093Y-211417D01*
X653217Y-212042D01*
X653571Y-212571D01*
X654100Y-212925D01*
X654724Y-213049D01*
X655349Y-212925D01*
X655709Y-212684D01*
X656069Y-212925D01*
X656693Y-213049D01*
X657317Y-212925D01*
X657677Y-212684D01*
X658037Y-212925D01*
X658661Y-213049D01*
X659286Y-212925D01*
X659815Y-212571D01*
X660169Y-212042D01*
X660293Y-211417D01*
X660169Y-210793D01*
X659815Y-210264D01*
X659634Y-210143D01*
Y-209542D01*
X659815Y-209421D01*
X660169Y-208892D01*
X660293Y-208268D01*
X660169Y-207643D01*
X659815Y-207114D01*
X659286Y-206761D01*
X658661Y-206636D01*
D02*
G37*
G36*
X361811Y-205455D02*
X361187Y-205579D01*
X360658Y-205933D01*
X360304Y-206462D01*
X360180Y-207087D01*
X360304Y-207711D01*
X360658Y-208240D01*
X361187Y-208594D01*
X361811Y-208718D01*
X362435Y-208594D01*
X362965Y-208240D01*
X363318Y-207711D01*
X363442Y-207087D01*
X363318Y-206462D01*
X362965Y-205933D01*
X362435Y-205579D01*
X361811Y-205455D01*
D02*
G37*
G36*
X86562Y-209551D02*
X85938Y-209676D01*
X85409Y-210029D01*
X85055Y-210558D01*
X84931Y-211183D01*
X85007Y-211565D01*
X85006Y-212075D01*
X84476Y-212429D01*
X84123Y-212958D01*
X83999Y-213583D01*
X84123Y-214207D01*
X84476Y-214736D01*
X85006Y-215090D01*
X85630Y-215214D01*
X86254Y-215090D01*
X86783Y-214736D01*
X87137Y-214207D01*
X87261Y-213583D01*
X87185Y-213200D01*
X87186Y-212690D01*
X87716Y-212336D01*
X88069Y-211807D01*
X88194Y-211183D01*
X88069Y-210558D01*
X87716Y-210029D01*
X87186Y-209676D01*
X86562Y-209551D01*
D02*
G37*
G36*
X-3728Y-205743D02*
X-13202D01*
Y-215217D01*
X-3728D01*
Y-205743D01*
D02*
G37*
G36*
X544291Y-213772D02*
X543667Y-213896D01*
X543138Y-214250D01*
X542784Y-214779D01*
X542660Y-215403D01*
X542784Y-216027D01*
X543138Y-216557D01*
X543667Y-216910D01*
X544291Y-217035D01*
X544916Y-216910D01*
X545445Y-216557D01*
X545798Y-216027D01*
X545923Y-215403D01*
X545798Y-214779D01*
X545445Y-214250D01*
X544916Y-213896D01*
X544291Y-213772D01*
D02*
G37*
G36*
X102528Y-209951D02*
X101903Y-210075D01*
X101374Y-210429D01*
X101020Y-210958D01*
X100896Y-211583D01*
X101020Y-212207D01*
X101191Y-212463D01*
X100964Y-213018D01*
X100754Y-213060D01*
X100224Y-213413D01*
X99871Y-213943D01*
X99767Y-214465D01*
X99566Y-214724D01*
X99308Y-214924D01*
X98785Y-215028D01*
X98256Y-215382D01*
X97902Y-215911D01*
X97778Y-216535D01*
X97902Y-217160D01*
X98256Y-217689D01*
X98785Y-218043D01*
X99410Y-218167D01*
X100034Y-218043D01*
X100563Y-217689D01*
X100917Y-217160D01*
X101021Y-216637D01*
X101221Y-216379D01*
X101479Y-216178D01*
X102002Y-216074D01*
X102532Y-215721D01*
X102885Y-215191D01*
X103009Y-214567D01*
X102885Y-213943D01*
X102714Y-213687D01*
X102941Y-213132D01*
X103152Y-213090D01*
X103681Y-212736D01*
X104035Y-212207D01*
X104159Y-211583D01*
X104035Y-210958D01*
X103681Y-210429D01*
X103152Y-210075D01*
X102528Y-209951D01*
D02*
G37*
G36*
X97125Y-217857D02*
X96501Y-217981D01*
X95972Y-218335D01*
X95618Y-218864D01*
X95494Y-219488D01*
X95618Y-220112D01*
X95972Y-220642D01*
X96501Y-220995D01*
X97125Y-221119D01*
X97750Y-220995D01*
X98279Y-220642D01*
X98632Y-220112D01*
X98757Y-219488D01*
X98632Y-218864D01*
X98279Y-218335D01*
X97750Y-217981D01*
X97125Y-217857D01*
D02*
G37*
G36*
X361531Y-221794D02*
X360906Y-221918D01*
X360377Y-222272D01*
X360284D01*
X359755Y-221918D01*
X359131Y-221794D01*
X358506Y-221918D01*
X357977Y-222272D01*
X357624Y-222801D01*
X357515Y-223347D01*
X357406Y-223483D01*
X357046Y-223709D01*
X356578Y-223616D01*
X356113Y-223335D01*
X356048Y-223011D01*
X355695Y-222482D01*
X355166Y-222129D01*
X354541Y-222004D01*
X353917Y-222129D01*
X353388Y-222482D01*
X353034Y-223011D01*
X352910Y-223636D01*
X353034Y-224260D01*
X353388Y-224789D01*
X353917Y-225143D01*
X354541Y-225267D01*
X355006Y-225548D01*
X355070Y-225871D01*
X355424Y-226400D01*
X355953Y-226754D01*
X356578Y-226878D01*
X357202Y-226754D01*
X357731Y-226400D01*
X358085Y-225871D01*
X358193Y-225325D01*
X358302Y-225189D01*
X358662Y-224963D01*
X359131Y-225057D01*
X359755Y-224932D01*
X360284Y-224579D01*
X360377D01*
X360906Y-224932D01*
X361531Y-225057D01*
X362155Y-224932D01*
X362684Y-224579D01*
X363038Y-224049D01*
X363162Y-223425D01*
X363038Y-222801D01*
X362684Y-222272D01*
X362155Y-221918D01*
X361531Y-221794D01*
D02*
G37*
G36*
X86614Y-219825D02*
X85990Y-219950D01*
X85461Y-220303D01*
X85107Y-220832D01*
X84983Y-221457D01*
X85107Y-222081D01*
X85461Y-222610D01*
X85990Y-222964D01*
X86614Y-223088D01*
X87239Y-222964D01*
X87768Y-222610D01*
X88121Y-222081D01*
X88245Y-221457D01*
X88121Y-220832D01*
X87768Y-220303D01*
X87239Y-219950D01*
X86614Y-219825D01*
D02*
G37*
G36*
X63976D02*
X63352Y-219950D01*
X62823Y-220303D01*
X62469Y-220832D01*
X62345Y-221457D01*
X62469Y-222081D01*
X62823Y-222610D01*
X63352Y-222964D01*
X63976Y-223088D01*
X64601Y-222964D01*
X65130Y-222610D01*
X65484Y-222081D01*
X65608Y-221457D01*
X65484Y-220832D01*
X65130Y-220303D01*
X64601Y-219950D01*
X63976Y-219825D01*
D02*
G37*
G36*
X544294Y-222616D02*
X543670Y-222740D01*
X543141Y-223094D01*
X542787Y-223623D01*
X542663Y-224248D01*
X542735Y-224608D01*
X542651Y-225084D01*
X542122Y-225437D01*
X541768Y-225967D01*
X541644Y-226591D01*
X541768Y-227215D01*
X542122Y-227744D01*
X542651Y-228098D01*
X543276Y-228222D01*
X543900Y-228098D01*
X544429Y-227744D01*
X544783Y-227215D01*
X544907Y-226591D01*
X544835Y-226230D01*
X544919Y-225755D01*
X545448Y-225401D01*
X545802Y-224872D01*
X545926Y-224248D01*
X545802Y-223623D01*
X545448Y-223094D01*
X544919Y-222740D01*
X544294Y-222616D01*
D02*
G37*
G36*
X86614Y-225731D02*
X85990Y-225855D01*
X85461Y-226209D01*
X85107Y-226738D01*
X84983Y-227362D01*
X85107Y-227987D01*
X85461Y-228516D01*
X85990Y-228869D01*
X86614Y-228994D01*
X87239Y-228869D01*
X87768Y-228516D01*
X88121Y-227987D01*
X88245Y-227362D01*
X88121Y-226738D01*
X87768Y-226209D01*
X87239Y-225855D01*
X86614Y-225731D01*
D02*
G37*
G36*
X611417Y-220781D02*
X610481Y-220968D01*
X609687Y-221498D01*
X609157Y-222292D01*
X608970Y-223228D01*
X609157Y-224165D01*
X609687Y-224959D01*
X610183Y-225290D01*
Y-225891D01*
X609687Y-226222D01*
X609157Y-227016D01*
X608970Y-227953D01*
X609157Y-228889D01*
X609687Y-229683D01*
X610481Y-230213D01*
X611417Y-230400D01*
X612354Y-230213D01*
X613148Y-229683D01*
X613678Y-228889D01*
X613864Y-227953D01*
X613678Y-227016D01*
X613148Y-226222D01*
X612652Y-225891D01*
Y-225290D01*
X613148Y-224959D01*
X613678Y-224165D01*
X613864Y-223228D01*
X613678Y-222292D01*
X613148Y-221498D01*
X612354Y-220968D01*
X611417Y-220781D01*
D02*
G37*
G36*
X604724Y-220388D02*
X603788Y-220574D01*
X602994Y-221104D01*
X602464Y-221898D01*
X602277Y-222835D01*
X602464Y-223771D01*
X602994Y-224565D01*
X603788Y-225095D01*
X604006Y-225139D01*
Y-225649D01*
X603788Y-225692D01*
X602994Y-226222D01*
X602464Y-227016D01*
X602277Y-227953D01*
X602464Y-228889D01*
X602994Y-229683D01*
X603788Y-230213D01*
X604724Y-230400D01*
X605661Y-230213D01*
X606455Y-229683D01*
X606985Y-228889D01*
X607171Y-227953D01*
X606985Y-227016D01*
X606455Y-226222D01*
X605661Y-225692D01*
X605443Y-225649D01*
Y-225139D01*
X605661Y-225095D01*
X606455Y-224565D01*
X606985Y-223771D01*
X607171Y-222835D01*
X606985Y-221898D01*
X606455Y-221104D01*
X605661Y-220574D01*
X604724Y-220388D01*
D02*
G37*
G36*
X599065Y-220585D02*
X598128Y-220771D01*
X597334Y-221301D01*
X596804Y-222095D01*
X596618Y-223031D01*
X596804Y-223968D01*
X597334Y-224762D01*
X598128Y-225292D01*
X598688Y-225404D01*
X598718Y-225410D01*
Y-225919D01*
X598665Y-225930D01*
X597883Y-226086D01*
X597089Y-226616D01*
X596558Y-227410D01*
X596372Y-228346D01*
X596558Y-229283D01*
X597089Y-230077D01*
X597883Y-230607D01*
X598819Y-230793D01*
X599755Y-230607D01*
X600549Y-230077D01*
X601080Y-229283D01*
X601266Y-228346D01*
X601080Y-227410D01*
X600549Y-226616D01*
X599755Y-226086D01*
X599196Y-225974D01*
X599165Y-225968D01*
Y-225459D01*
X599218Y-225448D01*
X600001Y-225292D01*
X600795Y-224762D01*
X601325Y-223968D01*
X601512Y-223031D01*
X601325Y-222095D01*
X600795Y-221301D01*
X600001Y-220771D01*
X599065Y-220585D01*
D02*
G37*
G36*
X-23622Y-227699D02*
X-24246Y-227823D01*
X-24776Y-228177D01*
X-25129Y-228706D01*
X-25253Y-229331D01*
X-25129Y-229955D01*
X-24776Y-230484D01*
X-24246Y-230838D01*
X-23622Y-230962D01*
X-22998Y-230838D01*
X-22468Y-230484D01*
X-22115Y-229955D01*
X-21991Y-229331D01*
X-22115Y-228706D01*
X-22468Y-228177D01*
X-22998Y-227823D01*
X-23622Y-227699D01*
D02*
G37*
G36*
X314503Y-223548D02*
X313878Y-223673D01*
X313349Y-224026D01*
X312995Y-224555D01*
X312871Y-225180D01*
X312995Y-225804D01*
X313349Y-226333D01*
X313462Y-226409D01*
X313711Y-226844D01*
X313579Y-227042D01*
X313357Y-227373D01*
X313233Y-227997D01*
X313357Y-228622D01*
X313711Y-229151D01*
X313723Y-229159D01*
X313836Y-229836D01*
X313719Y-230010D01*
X313595Y-230634D01*
X313719Y-231259D01*
X314073Y-231788D01*
X314602Y-232141D01*
X315226Y-232266D01*
X315851Y-232141D01*
X316380Y-231788D01*
X316734Y-231259D01*
X316858Y-230634D01*
X316734Y-230010D01*
X316380Y-229481D01*
X316368Y-229473D01*
X316255Y-228796D01*
X316372Y-228622D01*
X316496Y-227997D01*
X316372Y-227373D01*
X316018Y-226844D01*
X315905Y-226768D01*
X315656Y-226333D01*
X315789Y-226135D01*
X316010Y-225804D01*
X316134Y-225180D01*
X316010Y-224555D01*
X315656Y-224026D01*
X315127Y-223673D01*
X314503Y-223548D01*
D02*
G37*
G36*
X82677Y-230652D02*
X82053Y-230776D01*
X81524Y-231130D01*
X81170Y-231659D01*
X81046Y-232283D01*
X81170Y-232908D01*
X81524Y-233437D01*
X82053Y-233791D01*
X82677Y-233915D01*
X83302Y-233791D01*
X83831Y-233437D01*
X84184Y-232908D01*
X84308Y-232283D01*
X84184Y-231659D01*
X83831Y-231130D01*
X83302Y-230776D01*
X82677Y-230652D01*
D02*
G37*
G36*
X75787D02*
X75163Y-230776D01*
X74634Y-231130D01*
X74280Y-231659D01*
X74156Y-232283D01*
X74280Y-232908D01*
X74634Y-233437D01*
X75163Y-233791D01*
X75787Y-233915D01*
X76412Y-233791D01*
X76941Y-233437D01*
X77295Y-232908D01*
X77419Y-232283D01*
X77295Y-231659D01*
X76941Y-231130D01*
X76412Y-230776D01*
X75787Y-230652D01*
D02*
G37*
G36*
X361652Y-233573D02*
X361028Y-233698D01*
X360498Y-234051D01*
X360039Y-233838D01*
X359876Y-233729D01*
X359252Y-233605D01*
X358628Y-233729D01*
X358098Y-234083D01*
X358005D01*
X357476Y-233729D01*
X356852Y-233605D01*
X356228Y-233729D01*
X355698Y-234083D01*
X355606D01*
X355076Y-233729D01*
X354452Y-233605D01*
X353828Y-233729D01*
X353298Y-234083D01*
X352945Y-234612D01*
X352821Y-235236D01*
X352945Y-235860D01*
X353298Y-236390D01*
X353828Y-236743D01*
X354452Y-236868D01*
X355076Y-236743D01*
X355606Y-236390D01*
X355698D01*
X356228Y-236743D01*
X356852Y-236868D01*
X357476Y-236743D01*
X358005Y-236390D01*
X358098D01*
X358628Y-236743D01*
X359252Y-236868D01*
X359876Y-236743D01*
X360405Y-236390D01*
X360864Y-236603D01*
X361028Y-236712D01*
X361652Y-236836D01*
X362276Y-236712D01*
X362806Y-236358D01*
X363159Y-235829D01*
X363283Y-235205D01*
X363159Y-234580D01*
X362806Y-234051D01*
X362276Y-233698D01*
X361652Y-233573D01*
D02*
G37*
G36*
X544291Y-231636D02*
X543667Y-231761D01*
X543138Y-232114D01*
X542784Y-232643D01*
X542660Y-233268D01*
X542784Y-233892D01*
X543138Y-234421D01*
X543667Y-234775D01*
X544291Y-234899D01*
X544916Y-234775D01*
X545445Y-234421D01*
X545798Y-233892D01*
X545923Y-233268D01*
X545798Y-232643D01*
X545445Y-232114D01*
X544916Y-231761D01*
X544291Y-231636D01*
D02*
G37*
G36*
X-23622D02*
X-24246Y-231761D01*
X-24776Y-232114D01*
X-25129Y-232643D01*
X-25253Y-233268D01*
X-25129Y-233892D01*
X-24776Y-234421D01*
X-24246Y-234775D01*
X-23622Y-234899D01*
X-22998Y-234775D01*
X-22468Y-234421D01*
X-22115Y-233892D01*
X-21991Y-233268D01*
X-22115Y-232643D01*
X-22468Y-232114D01*
X-22998Y-231761D01*
X-23622Y-231636D01*
D02*
G37*
G36*
X323819Y-225731D02*
X323195Y-225855D01*
X322665Y-226209D01*
X322312Y-226738D01*
X322188Y-227362D01*
X322312Y-227987D01*
X322665Y-228516D01*
X323195Y-228869D01*
X323723Y-228975D01*
X323745Y-228991D01*
X323848Y-229592D01*
X323800Y-229672D01*
X323195Y-229792D01*
X322665Y-230146D01*
X322312Y-230675D01*
X322188Y-231299D01*
X322312Y-231924D01*
X322665Y-232453D01*
X323195Y-232806D01*
X323819Y-232931D01*
X324172Y-233283D01*
X324156Y-233362D01*
X324280Y-233986D01*
X324634Y-234516D01*
X325163Y-234869D01*
X325787Y-234994D01*
X326412Y-234869D01*
X326941Y-234516D01*
X327295Y-233986D01*
X327419Y-233362D01*
X327295Y-232738D01*
X326941Y-232209D01*
X326412Y-231855D01*
X325787Y-231731D01*
X325483Y-231427D01*
X325470Y-231376D01*
X325787Y-230994D01*
X326412Y-230869D01*
X326941Y-230516D01*
X327295Y-229987D01*
X327419Y-229362D01*
X327295Y-228738D01*
X326941Y-228209D01*
X326412Y-227855D01*
X325883Y-227750D01*
X325590Y-227534D01*
X325564Y-227507D01*
X325436Y-227291D01*
X325326Y-226738D01*
X324972Y-226209D01*
X324443Y-225855D01*
X323819Y-225731D01*
D02*
G37*
G36*
X288583Y-223959D02*
X287958Y-224083D01*
X287429Y-224437D01*
X287075Y-224966D01*
X286951Y-225590D01*
X287075Y-226215D01*
X287429Y-226744D01*
X287447Y-226756D01*
X287472Y-226855D01*
X287413Y-227334D01*
X287035Y-227587D01*
X286682Y-228116D01*
X286558Y-228740D01*
X286682Y-229364D01*
X287035Y-229894D01*
Y-229949D01*
X286682Y-230478D01*
X286558Y-231102D01*
X286682Y-231727D01*
X287026Y-232242D01*
X286904Y-232324D01*
X286550Y-232854D01*
X286426Y-233478D01*
X286550Y-234102D01*
X286904Y-234631D01*
X287433Y-234985D01*
X288057Y-235109D01*
X288681Y-234985D01*
X289211Y-234631D01*
X289564Y-234102D01*
X289688Y-233478D01*
X289564Y-232854D01*
X289220Y-232338D01*
X289342Y-232256D01*
X289696Y-231727D01*
X289820Y-231102D01*
X289696Y-230478D01*
X289342Y-229949D01*
Y-229894D01*
X289696Y-229364D01*
X289820Y-228740D01*
X289696Y-228116D01*
X289342Y-227587D01*
X289325Y-227575D01*
X289300Y-227476D01*
X289359Y-226996D01*
X289736Y-226744D01*
X290090Y-226215D01*
X290214Y-225590D01*
X290090Y-224966D01*
X289736Y-224437D01*
X289207Y-224083D01*
X288583Y-223959D01*
D02*
G37*
G36*
X564896Y-235168D02*
X564310Y-235284D01*
X563814Y-235616D01*
X563483Y-236112D01*
X563366Y-236697D01*
X563483Y-237282D01*
X563814Y-237779D01*
X564310Y-238110D01*
X564896Y-238227D01*
X565481Y-238110D01*
X565977Y-237779D01*
X566309Y-237282D01*
X566425Y-236697D01*
X566309Y-236112D01*
X565977Y-235616D01*
X565481Y-235284D01*
X564896Y-235168D01*
D02*
G37*
G36*
X-23622Y-235573D02*
X-24246Y-235698D01*
X-24776Y-236051D01*
X-25129Y-236580D01*
X-25253Y-237205D01*
X-25129Y-237829D01*
X-24776Y-238358D01*
X-24246Y-238712D01*
X-23622Y-238836D01*
X-22998Y-238712D01*
X-22468Y-238358D01*
X-22115Y-237829D01*
X-21991Y-237205D01*
X-22115Y-236580D01*
X-22468Y-236051D01*
X-22998Y-235698D01*
X-23622Y-235573D01*
D02*
G37*
G36*
X78740Y-236410D02*
X78116Y-236534D01*
X77587Y-236887D01*
X77233Y-237417D01*
X77109Y-238041D01*
X77233Y-238665D01*
X77587Y-239194D01*
X78116Y-239548D01*
X78740Y-239672D01*
X79364Y-239548D01*
X79894Y-239194D01*
X80247Y-238665D01*
X80371Y-238041D01*
X80247Y-237417D01*
X79894Y-236887D01*
X79364Y-236534D01*
X78740Y-236410D01*
D02*
G37*
G36*
X-23622Y-239510D02*
X-24246Y-239635D01*
X-24776Y-239988D01*
X-25129Y-240517D01*
X-25253Y-241142D01*
X-25129Y-241766D01*
X-24776Y-242295D01*
X-24246Y-242649D01*
X-23622Y-242773D01*
X-22998Y-242649D01*
X-22468Y-242295D01*
X-22115Y-241766D01*
X-21991Y-241142D01*
X-22115Y-240517D01*
X-22468Y-239988D01*
X-22998Y-239635D01*
X-23622Y-239510D01*
D02*
G37*
G36*
X323850Y-235573D02*
X323226Y-235698D01*
X322697Y-236051D01*
X322343Y-236580D01*
X322219Y-237205D01*
X322343Y-237829D01*
X322697Y-238358D01*
X323226Y-238712D01*
X323725Y-238811D01*
X323823Y-238901D01*
X323780Y-239517D01*
X323719Y-239568D01*
X323226Y-239666D01*
X322697Y-240020D01*
X322343Y-240549D01*
X322219Y-241173D01*
X322343Y-241797D01*
X322697Y-242327D01*
X323226Y-242680D01*
X323731Y-242781D01*
X324103Y-243114D01*
X324165Y-243252D01*
X324280Y-243829D01*
X324634Y-244358D01*
X325163Y-244712D01*
X325787Y-244836D01*
X326412Y-244712D01*
X326941Y-244358D01*
X327295Y-243829D01*
X327419Y-243205D01*
X327295Y-242580D01*
X326941Y-242051D01*
X326412Y-241698D01*
X325907Y-241597D01*
X325783Y-241486D01*
X325835Y-240880D01*
X325919Y-240810D01*
X326412Y-240712D01*
X326941Y-240358D01*
X327295Y-239829D01*
X327419Y-239205D01*
X327295Y-238580D01*
X326941Y-238051D01*
X326412Y-237698D01*
X325913Y-237598D01*
X325559Y-237275D01*
X325466Y-237127D01*
X325358Y-236580D01*
X325004Y-236051D01*
X324475Y-235698D01*
X323850Y-235573D01*
D02*
G37*
G36*
X640945Y-244825D02*
X640321Y-244950D01*
X639791Y-245303D01*
X639671Y-245484D01*
X639069D01*
X638949Y-245303D01*
X638420Y-244950D01*
X637795Y-244825D01*
X637171Y-244950D01*
X636642Y-245303D01*
X636288Y-245832D01*
X636164Y-246457D01*
X636288Y-247081D01*
X636529Y-247441D01*
X636288Y-247801D01*
X636164Y-248425D01*
X636288Y-249049D01*
X636529Y-249409D01*
X636288Y-249769D01*
X636164Y-250394D01*
X636288Y-251018D01*
X636642Y-251547D01*
X637171Y-251901D01*
X637795Y-252025D01*
X638420Y-251901D01*
X638949Y-251547D01*
X639069Y-251367D01*
X639671D01*
X639791Y-251547D01*
X640321Y-251901D01*
X640945Y-252025D01*
X641569Y-251901D01*
X642098Y-251547D01*
X642452Y-251018D01*
X642576Y-250394D01*
X642452Y-249769D01*
X642211Y-249409D01*
X642452Y-249049D01*
X642576Y-248425D01*
X642452Y-247801D01*
X642211Y-247441D01*
X642452Y-247081D01*
X642576Y-246457D01*
X642452Y-245832D01*
X642098Y-245303D01*
X641569Y-244950D01*
X640945Y-244825D01*
D02*
G37*
G36*
X314658Y-243143D02*
X314034Y-243268D01*
X313504Y-243621D01*
X313151Y-244150D01*
X313026Y-244775D01*
X313151Y-245399D01*
X313504Y-245928D01*
X314034Y-246282D01*
X314658Y-246406D01*
X315282Y-246282D01*
X315811Y-245928D01*
X316165Y-245399D01*
X316289Y-244775D01*
X316165Y-244150D01*
X315811Y-243621D01*
X315282Y-243268D01*
X314658Y-243143D01*
D02*
G37*
G36*
X288057Y-243464D02*
X287433Y-243588D01*
X286904Y-243941D01*
X286550Y-244471D01*
X286426Y-245095D01*
X286550Y-245719D01*
X286904Y-246249D01*
X286826Y-246798D01*
X286682Y-247013D01*
X286558Y-247638D01*
X286682Y-248262D01*
X287035Y-248791D01*
X287565Y-249145D01*
X288189Y-249269D01*
X288813Y-249145D01*
X289342Y-248791D01*
X289696Y-248262D01*
X289820Y-247638D01*
X289696Y-247013D01*
X289471Y-246676D01*
X289211Y-246249D01*
X289564Y-245719D01*
X289688Y-245095D01*
X289564Y-244471D01*
X289211Y-243941D01*
X288682Y-243588D01*
X288057Y-243464D01*
D02*
G37*
G36*
X555364Y-247778D02*
X554740Y-247902D01*
X554210Y-248256D01*
X553857Y-248785D01*
X553732Y-249410D01*
X553857Y-250034D01*
X554210Y-250563D01*
X554740Y-250917D01*
X555364Y-251041D01*
X555988Y-250917D01*
X556517Y-250563D01*
X556871Y-250034D01*
X556995Y-249410D01*
X556871Y-248785D01*
X556517Y-248256D01*
X555988Y-247902D01*
X555364Y-247778D01*
D02*
G37*
G36*
X360204Y-251353D02*
X359580Y-251477D01*
X359051Y-251831D01*
X358697Y-252360D01*
X358573Y-252984D01*
X358697Y-253608D01*
X359051Y-254138D01*
X359580Y-254491D01*
X360204Y-254616D01*
X360829Y-254491D01*
X361358Y-254138D01*
X361712Y-253608D01*
X361836Y-252984D01*
X361712Y-252360D01*
X361358Y-251831D01*
X360829Y-251477D01*
X360204Y-251353D01*
D02*
G37*
G36*
X360236Y-260554D02*
X359612Y-260679D01*
X359083Y-261032D01*
X358729Y-261561D01*
X358605Y-262186D01*
X358729Y-262810D01*
X359083Y-263339D01*
X359612Y-263693D01*
X360236Y-263817D01*
X360860Y-263693D01*
X361390Y-263339D01*
X361743Y-262810D01*
X361868Y-262186D01*
X361743Y-261561D01*
X361390Y-261032D01*
X360860Y-260679D01*
X360236Y-260554D01*
D02*
G37*
G36*
X121063Y-262000D02*
X120439Y-262124D01*
X119910Y-262478D01*
X119556Y-263007D01*
X119432Y-263632D01*
X119556Y-264256D01*
X119910Y-264785D01*
X120439Y-265139D01*
X121063Y-265263D01*
X121687Y-265139D01*
X122216Y-264785D01*
X122570Y-264256D01*
X122694Y-263632D01*
X122570Y-263007D01*
X122216Y-262478D01*
X121687Y-262124D01*
X121063Y-262000D01*
D02*
G37*
G36*
X106299D02*
X105675Y-262124D01*
X105146Y-262478D01*
X104792Y-263007D01*
X104668Y-263632D01*
X104792Y-264256D01*
X105146Y-264785D01*
X105675Y-265139D01*
X106299Y-265263D01*
X106923Y-265139D01*
X107453Y-264785D01*
X107806Y-264256D01*
X107931Y-263632D01*
X107806Y-263007D01*
X107453Y-262478D01*
X106923Y-262124D01*
X106299Y-262000D01*
D02*
G37*
G36*
X85630Y-262148D02*
X85006Y-262272D01*
X84476Y-262626D01*
X84123Y-263155D01*
X83999Y-263779D01*
X84123Y-264404D01*
X84476Y-264933D01*
Y-265026D01*
X84123Y-265555D01*
X83999Y-266179D01*
X84123Y-266804D01*
X84476Y-267333D01*
X85006Y-267687D01*
X85630Y-267811D01*
X86254Y-267687D01*
X86783Y-267333D01*
X87137Y-266804D01*
X87261Y-266179D01*
X87137Y-265555D01*
X86783Y-265026D01*
Y-264933D01*
X87137Y-264404D01*
X87261Y-263779D01*
X87137Y-263155D01*
X86783Y-262626D01*
X86254Y-262272D01*
X85630Y-262148D01*
D02*
G37*
G36*
X-3728Y-258893D02*
X-13202D01*
Y-268367D01*
X-3728D01*
Y-258893D01*
D02*
G37*
G36*
X360236Y-264554D02*
X359612Y-264679D01*
X359083Y-265032D01*
X358729Y-265562D01*
X358605Y-266186D01*
X358729Y-266810D01*
X359083Y-267339D01*
Y-267432D01*
X358729Y-267962D01*
X358605Y-268586D01*
X358729Y-269210D01*
X359083Y-269739D01*
X359612Y-270093D01*
X360236Y-270217D01*
X360860Y-270093D01*
X361390Y-269739D01*
X361743Y-269210D01*
X361868Y-268586D01*
X361743Y-267962D01*
X361390Y-267432D01*
Y-267339D01*
X361743Y-266810D01*
X361868Y-266186D01*
X361743Y-265562D01*
X361390Y-265032D01*
X360860Y-264679D01*
X360236Y-264554D01*
D02*
G37*
G36*
X512402Y-260327D02*
X511777Y-260451D01*
X511248Y-260805D01*
X510894Y-261334D01*
X510770Y-261958D01*
X510894Y-262583D01*
X511248Y-263112D01*
X511428Y-263232D01*
Y-263834D01*
X511248Y-263954D01*
X510894Y-264484D01*
X510770Y-265108D01*
X510894Y-265732D01*
X511248Y-266261D01*
X511355Y-266333D01*
X511389Y-266912D01*
X511036Y-267441D01*
X510912Y-268065D01*
X511036Y-268689D01*
X511389Y-269219D01*
X511504Y-269295D01*
Y-269309D01*
X511150Y-269838D01*
X511026Y-270462D01*
X511150Y-271087D01*
X511504Y-271616D01*
X512033Y-271970D01*
X512657Y-272094D01*
X513282Y-271970D01*
X513811Y-271616D01*
X514164Y-271087D01*
X514289Y-270462D01*
X514164Y-269838D01*
X513811Y-269309D01*
X513696Y-269233D01*
Y-269219D01*
X514050Y-268689D01*
X514174Y-268065D01*
X514050Y-267441D01*
X513696Y-266912D01*
X513589Y-266840D01*
X513555Y-266261D01*
X513909Y-265732D01*
X514033Y-265108D01*
X513909Y-264484D01*
X513555Y-263954D01*
X513375Y-263834D01*
Y-263232D01*
X513555Y-263112D01*
X513909Y-262583D01*
X514033Y-261958D01*
X513909Y-261334D01*
X513555Y-260805D01*
X513026Y-260451D01*
X512402Y-260327D01*
D02*
G37*
G36*
X360236Y-270858D02*
X359612Y-270983D01*
X359083Y-271336D01*
X358729Y-271866D01*
X358605Y-272490D01*
X358729Y-273114D01*
X359083Y-273643D01*
X359612Y-273997D01*
X360236Y-274121D01*
X360860Y-273997D01*
X361390Y-273643D01*
X361743Y-273114D01*
X361868Y-272490D01*
X361743Y-271866D01*
X361390Y-271336D01*
X360860Y-270983D01*
X360236Y-270858D01*
D02*
G37*
G36*
X320866D02*
X320242Y-270983D01*
X319713Y-271336D01*
X319359Y-271866D01*
X319235Y-272490D01*
X319359Y-273114D01*
X319713Y-273643D01*
X320242Y-273997D01*
X320866Y-274121D01*
X321490Y-273997D01*
X322020Y-273643D01*
X322373Y-273114D01*
X322498Y-272490D01*
X322373Y-271866D01*
X322020Y-271336D01*
X321490Y-270983D01*
X320866Y-270858D01*
D02*
G37*
G36*
X340904Y-271490D02*
X340170Y-271636D01*
X339547Y-272052D01*
X339131Y-272675D01*
X338984Y-273410D01*
X339131Y-274145D01*
X339547Y-274768D01*
X340170Y-275184D01*
X340904Y-275330D01*
X341639Y-275184D01*
X342262Y-274768D01*
X342678Y-274145D01*
X342824Y-273410D01*
X342678Y-272675D01*
X342262Y-272052D01*
X341639Y-271636D01*
X340904Y-271490D01*
D02*
G37*
G36*
X528395Y-271500D02*
X527661Y-271646D01*
X527038Y-272062D01*
X526622Y-272685D01*
X526475Y-273420D01*
X526622Y-274154D01*
X527038Y-274777D01*
X527661Y-275194D01*
X528395Y-275340D01*
X529130Y-275194D01*
X529753Y-274777D01*
X530169Y-274154D01*
X530315Y-273420D01*
X530169Y-272685D01*
X529753Y-272062D01*
X529130Y-271646D01*
X528395Y-271500D01*
D02*
G37*
G36*
X87598Y-273959D02*
X86974Y-274083D01*
X86445Y-274437D01*
X86091Y-274966D01*
X85967Y-275590D01*
X86091Y-276215D01*
X86445Y-276744D01*
X86974Y-277098D01*
X87598Y-277222D01*
X88223Y-277098D01*
X88752Y-276744D01*
X89106Y-276215D01*
X89230Y-275590D01*
X89106Y-274966D01*
X88752Y-274437D01*
X88223Y-274083D01*
X87598Y-273959D01*
D02*
G37*
G36*
X63976D02*
X63352Y-274083D01*
X62823Y-274437D01*
X62469Y-274966D01*
X62345Y-275590D01*
X62469Y-276215D01*
X62823Y-276744D01*
X63352Y-277098D01*
X63976Y-277222D01*
X64601Y-277098D01*
X65130Y-276744D01*
X65484Y-276215D01*
X65608Y-275590D01*
X65484Y-274966D01*
X65130Y-274437D01*
X64601Y-274083D01*
X63976Y-273959D01*
D02*
G37*
G36*
X87598Y-279865D02*
X86974Y-279989D01*
X86445Y-280343D01*
X86091Y-280872D01*
X85967Y-281496D01*
X86091Y-282120D01*
X86445Y-282650D01*
X86974Y-283003D01*
X87598Y-283127D01*
X88223Y-283003D01*
X88752Y-282650D01*
X89106Y-282120D01*
X89230Y-281496D01*
X89106Y-280872D01*
X88752Y-280343D01*
X88223Y-279989D01*
X87598Y-279865D01*
D02*
G37*
G36*
X-23622Y-280849D02*
X-24246Y-280973D01*
X-24776Y-281327D01*
X-25129Y-281856D01*
X-25253Y-282480D01*
X-25129Y-283105D01*
X-24776Y-283634D01*
X-24246Y-283987D01*
X-23622Y-284112D01*
X-22998Y-283987D01*
X-22468Y-283634D01*
X-22115Y-283105D01*
X-21991Y-282480D01*
X-22115Y-281856D01*
X-22468Y-281327D01*
X-22998Y-280973D01*
X-23622Y-280849D01*
D02*
G37*
G36*
X26575Y-281833D02*
X25951Y-281957D01*
X25421Y-282311D01*
X25068Y-282840D01*
X24943Y-283465D01*
X25068Y-284089D01*
X25421Y-284618D01*
X25951Y-284972D01*
X26575Y-285096D01*
X27199Y-284972D01*
X27728Y-284618D01*
X28082Y-284089D01*
X28206Y-283465D01*
X28082Y-282840D01*
X27728Y-282311D01*
X27199Y-281957D01*
X26575Y-281833D01*
D02*
G37*
G36*
X75787Y-283802D02*
X75163Y-283926D01*
X74634Y-284279D01*
X74280Y-284809D01*
X74156Y-285433D01*
X74280Y-286057D01*
X74634Y-286587D01*
X75163Y-286940D01*
X75787Y-287064D01*
X76412Y-286940D01*
X76941Y-286587D01*
X77295Y-286057D01*
X77419Y-285433D01*
X77295Y-284809D01*
X76941Y-284279D01*
X76412Y-283926D01*
X75787Y-283802D01*
D02*
G37*
G36*
X-23622Y-284786D02*
X-24246Y-284910D01*
X-24776Y-285264D01*
X-25129Y-285793D01*
X-25253Y-286417D01*
X-25129Y-287042D01*
X-24776Y-287571D01*
X-24246Y-287925D01*
X-23622Y-288049D01*
X-22998Y-287925D01*
X-22468Y-287571D01*
X-22115Y-287042D01*
X-21991Y-286417D01*
X-22115Y-285793D01*
X-22468Y-285264D01*
X-22998Y-284910D01*
X-23622Y-284786D01*
D02*
G37*
G36*
X81880Y-285951D02*
X81255Y-286075D01*
X80726Y-286429D01*
X80372Y-286958D01*
X80248Y-287582D01*
X80372Y-288207D01*
X80726Y-288736D01*
X81255Y-289090D01*
X81880Y-289214D01*
X82504Y-289090D01*
X83033Y-288736D01*
X83387Y-288207D01*
X83511Y-287582D01*
X83387Y-286958D01*
X83033Y-286429D01*
X82504Y-286075D01*
X81880Y-285951D01*
D02*
G37*
G36*
X-23622Y-288723D02*
X-24246Y-288847D01*
X-24776Y-289201D01*
X-25129Y-289730D01*
X-25253Y-290354D01*
X-25129Y-290979D01*
X-24776Y-291508D01*
X-24246Y-291862D01*
X-23622Y-291986D01*
X-22998Y-291862D01*
X-22468Y-291508D01*
X-22115Y-290979D01*
X-21991Y-290354D01*
X-22115Y-289730D01*
X-22468Y-289201D01*
X-22998Y-288847D01*
X-23622Y-288723D01*
D02*
G37*
G36*
Y-292660D02*
X-24246Y-292784D01*
X-24776Y-293138D01*
X-25129Y-293667D01*
X-25253Y-294291D01*
X-25129Y-294916D01*
X-24776Y-295445D01*
X-24246Y-295798D01*
X-23622Y-295923D01*
X-22998Y-295798D01*
X-22468Y-295445D01*
X-22115Y-294916D01*
X-21991Y-294291D01*
X-22115Y-293667D01*
X-22468Y-293138D01*
X-22998Y-292784D01*
X-23622Y-292660D01*
D02*
G37*
G36*
X675591Y-297188D02*
X674966Y-297312D01*
X674606Y-297552D01*
X674246Y-297312D01*
X673622Y-297188D01*
X672998Y-297312D01*
X672638Y-297552D01*
X672278Y-297312D01*
X671654Y-297188D01*
X671029Y-297312D01*
X670500Y-297665D01*
X670146Y-298195D01*
X670022Y-298819D01*
X670146Y-299443D01*
X670500Y-299972D01*
X670681Y-300093D01*
Y-300694D01*
X670500Y-300815D01*
X670146Y-301344D01*
X670022Y-301969D01*
X670146Y-302593D01*
X670500Y-303122D01*
X671029Y-303476D01*
X671654Y-303600D01*
X672278Y-303476D01*
X672638Y-303235D01*
X672998Y-303476D01*
X673622Y-303600D01*
X674246Y-303476D01*
X674606Y-303235D01*
X674966Y-303476D01*
X675591Y-303600D01*
X676215Y-303476D01*
X676744Y-303122D01*
X677098Y-302593D01*
X677222Y-301969D01*
X677098Y-301344D01*
X676744Y-300815D01*
X676564Y-300694D01*
Y-300093D01*
X676744Y-299972D01*
X677098Y-299443D01*
X677222Y-298819D01*
X677098Y-298195D01*
X676744Y-297665D01*
X676215Y-297312D01*
X675591Y-297188D01*
D02*
G37*
G36*
X588976Y-301125D02*
X588352Y-301249D01*
X587823Y-301602D01*
X587469Y-302132D01*
X587345Y-302756D01*
X587469Y-303380D01*
X587823Y-303909D01*
X588352Y-304263D01*
X588976Y-304387D01*
X589601Y-304263D01*
X590130Y-303909D01*
X590484Y-303380D01*
X590608Y-302756D01*
X590484Y-302132D01*
X590130Y-301602D01*
X589601Y-301249D01*
X588976Y-301125D01*
D02*
G37*
G36*
X579528Y-301518D02*
X578903Y-301642D01*
X578374Y-301996D01*
X578020Y-302525D01*
X577896Y-303150D01*
X578020Y-303774D01*
X578374Y-304303D01*
X578903Y-304657D01*
X579528Y-304781D01*
X580152Y-304657D01*
X580681Y-304303D01*
X581035Y-303774D01*
X581159Y-303150D01*
X581035Y-302525D01*
X580681Y-301996D01*
X580152Y-301642D01*
X579528Y-301518D01*
D02*
G37*
G36*
X453937Y-305110D02*
X453313Y-305235D01*
X452783Y-305588D01*
X452335D01*
X451805Y-305235D01*
X451181Y-305110D01*
X450557Y-305235D01*
X450028Y-305588D01*
X449907Y-305769D01*
X449306D01*
X449185Y-305588D01*
X448656Y-305235D01*
X448032Y-305110D01*
X447407Y-305235D01*
X446878Y-305588D01*
X446429D01*
X445900Y-305235D01*
X445276Y-305110D01*
X444651Y-305235D01*
X444122Y-305588D01*
X444001Y-305769D01*
X443400D01*
X443280Y-305588D01*
X442750Y-305235D01*
X442126Y-305110D01*
X441502Y-305235D01*
X440973Y-305588D01*
X440524D01*
X439994Y-305235D01*
X439370Y-305110D01*
X438746Y-305235D01*
X438217Y-305588D01*
X438096Y-305769D01*
X437495D01*
X437374Y-305588D01*
X436845Y-305235D01*
X436221Y-305110D01*
X435596Y-305235D01*
X435067Y-305588D01*
X434618D01*
X434089Y-305235D01*
X433465Y-305110D01*
X432840Y-305235D01*
X432311Y-305588D01*
X431957Y-306117D01*
X431833Y-306742D01*
X431957Y-307366D01*
X432311Y-307895D01*
X432840Y-308249D01*
X433465Y-308373D01*
X434089Y-308249D01*
X434618Y-307895D01*
X435067D01*
X435596Y-308249D01*
X436221Y-308373D01*
X436845Y-308249D01*
X437374Y-307895D01*
X437495Y-307715D01*
X438096D01*
X438217Y-307895D01*
X438746Y-308249D01*
X439370Y-308373D01*
X439994Y-308249D01*
X440524Y-307895D01*
X440973D01*
X441502Y-308249D01*
X442126Y-308373D01*
X442750Y-308249D01*
X443280Y-307895D01*
X443400Y-307715D01*
X444001D01*
X444122Y-307895D01*
X444651Y-308249D01*
X445276Y-308373D01*
X445900Y-308249D01*
X446429Y-307895D01*
X446878D01*
X447407Y-308249D01*
X448032Y-308373D01*
X448656Y-308249D01*
X449185Y-307895D01*
X449306Y-307715D01*
X449907D01*
X450028Y-307895D01*
X450557Y-308249D01*
X451181Y-308373D01*
X451805Y-308249D01*
X452335Y-307895D01*
X452783D01*
X453313Y-308249D01*
X453937Y-308373D01*
X454561Y-308249D01*
X455091Y-307895D01*
X455444Y-307366D01*
X455568Y-306742D01*
X455444Y-306117D01*
X455091Y-305588D01*
X454561Y-305235D01*
X453937Y-305110D01*
D02*
G37*
G36*
X470275Y-306678D02*
X469540Y-306824D01*
X468917Y-307240D01*
X468501Y-307863D01*
X468355Y-308597D01*
X468501Y-309332D01*
X468917Y-309955D01*
X469540Y-310371D01*
X470275Y-310517D01*
X471009Y-310371D01*
X471632Y-309955D01*
X472049Y-309332D01*
X472195Y-308597D01*
X472049Y-307863D01*
X471632Y-307240D01*
X471009Y-306824D01*
X470275Y-306678D01*
D02*
G37*
G36*
X391535D02*
X390800Y-306824D01*
X390177Y-307240D01*
X389761Y-307863D01*
X389615Y-308597D01*
X389761Y-309332D01*
X390177Y-309955D01*
X390800Y-310371D01*
X391535Y-310517D01*
X392269Y-310371D01*
X392892Y-309955D01*
X393309Y-309332D01*
X393455Y-308597D01*
X393309Y-307863D01*
X392892Y-307240D01*
X392269Y-306824D01*
X391535Y-306678D01*
D02*
G37*
G36*
X634252Y-312936D02*
X633628Y-313060D01*
X633098Y-313413D01*
X632745Y-313943D01*
X632621Y-314567D01*
X632745Y-315191D01*
X633098Y-315721D01*
X633628Y-316074D01*
X634252Y-316198D01*
X634876Y-316074D01*
X635405Y-315721D01*
X635759Y-315191D01*
X635883Y-314567D01*
X635759Y-313943D01*
X635405Y-313413D01*
X634876Y-313060D01*
X634252Y-312936D01*
D02*
G37*
G36*
X653150Y-312936D02*
X652525Y-313060D01*
X651996Y-313413D01*
X651642Y-313943D01*
X651518Y-314567D01*
X651642Y-315191D01*
X651996Y-315721D01*
X652525Y-316074D01*
X653150Y-316198D01*
X653774Y-316074D01*
X654303Y-315721D01*
X654657Y-315191D01*
X654781Y-314567D01*
X654657Y-313943D01*
X654303Y-313413D01*
X653774Y-313060D01*
X653150Y-312936D01*
D02*
G37*
G36*
X533015Y-306026D02*
X531701Y-306155D01*
X530437Y-306539D01*
X529272Y-307162D01*
X528251Y-308000D01*
X527413Y-309021D01*
X526790Y-310186D01*
X526407Y-311450D01*
X526277Y-312764D01*
X526407Y-314078D01*
X526790Y-315342D01*
X527413Y-316507D01*
X528251Y-317529D01*
X529272Y-318366D01*
X530437Y-318989D01*
X531701Y-319373D01*
X533015Y-319502D01*
X534330Y-319373D01*
X535594Y-318989D01*
X536759Y-318366D01*
X537780Y-317529D01*
X538618Y-316507D01*
X539240Y-315342D01*
X539624Y-314078D01*
X539753Y-312764D01*
X539624Y-311450D01*
X539240Y-310186D01*
X538618Y-309021D01*
X537780Y-308000D01*
X536759Y-307162D01*
X535594Y-306539D01*
X534330Y-306155D01*
X533015Y-306026D01*
D02*
G37*
G36*
X336515D02*
X335201Y-306155D01*
X333937Y-306539D01*
X332772Y-307162D01*
X331751Y-308000D01*
X330913Y-309021D01*
X330290Y-310186D01*
X329907Y-311450D01*
X329777Y-312764D01*
X329907Y-314078D01*
X330290Y-315342D01*
X330913Y-316507D01*
X331751Y-317529D01*
X332772Y-318366D01*
X333937Y-318989D01*
X335201Y-319373D01*
X336515Y-319502D01*
X337830Y-319373D01*
X339094Y-318989D01*
X340259Y-318366D01*
X341280Y-317529D01*
X342118Y-316507D01*
X342740Y-315342D01*
X343124Y-314078D01*
X343253Y-312764D01*
X343124Y-311450D01*
X342740Y-310186D01*
X342118Y-309021D01*
X341280Y-308000D01*
X340259Y-307162D01*
X339094Y-306539D01*
X337830Y-306155D01*
X336515Y-306026D01*
D02*
G37*
G36*
X142520Y-311946D02*
X141332Y-312103D01*
X140225Y-312561D01*
X139275Y-313290D01*
X138545Y-314241D01*
X138087Y-315348D01*
X137930Y-316535D01*
X138087Y-317723D01*
X138545Y-318830D01*
X139275Y-319780D01*
X140225Y-320510D01*
X141332Y-320968D01*
X142520Y-321125D01*
X143708Y-320968D01*
X144814Y-320510D01*
X145765Y-319780D01*
X146494Y-318830D01*
X146953Y-317723D01*
X147109Y-316535D01*
X146953Y-315348D01*
X146494Y-314241D01*
X145765Y-313290D01*
X144814Y-312561D01*
X143708Y-312103D01*
X142520Y-311946D01*
D02*
G37*
G36*
X-3728Y-312044D02*
X-13202D01*
Y-321518D01*
X-3728D01*
Y-312044D01*
D02*
G37*
G36*
X85416Y-316068D02*
X84791Y-316192D01*
X84262Y-316546D01*
X83908Y-317075D01*
X83784Y-317699D01*
X83908Y-318323D01*
X84262Y-318853D01*
X84274Y-319462D01*
X84123Y-319689D01*
X83999Y-320313D01*
X84123Y-320938D01*
X84476Y-321467D01*
X85006Y-321821D01*
X85630Y-321945D01*
X86254Y-321821D01*
X86783Y-321467D01*
X87137Y-320938D01*
X87261Y-320313D01*
X87137Y-319689D01*
X86783Y-319160D01*
X86771Y-318550D01*
X86923Y-318323D01*
X87047Y-317699D01*
X86923Y-317075D01*
X86569Y-316546D01*
X86040Y-316192D01*
X85416Y-316068D01*
D02*
G37*
G36*
X447244Y-323221D02*
X446620Y-323345D01*
X446091Y-323698D01*
X445642D01*
X445113Y-323345D01*
X444488Y-323221D01*
X443864Y-323345D01*
X443335Y-323698D01*
X442981Y-324228D01*
X442857Y-324852D01*
X442981Y-325476D01*
X443335Y-326006D01*
X443864Y-326359D01*
X444488Y-326483D01*
X445113Y-326359D01*
X445642Y-326006D01*
X446091D01*
X446620Y-326359D01*
X447244Y-326483D01*
X447868Y-326359D01*
X448398Y-326006D01*
X448751Y-325476D01*
X448876Y-324852D01*
X448751Y-324228D01*
X448398Y-323698D01*
X447868Y-323345D01*
X447244Y-323221D01*
D02*
G37*
G36*
X440551D02*
X439927Y-323345D01*
X439398Y-323698D01*
X438949D01*
X438420Y-323345D01*
X437795Y-323221D01*
X437171Y-323345D01*
X436642Y-323698D01*
X436288Y-324228D01*
X436164Y-324852D01*
X436288Y-325476D01*
X436642Y-326006D01*
X437171Y-326359D01*
X437795Y-326483D01*
X438420Y-326359D01*
X438949Y-326006D01*
X439398D01*
X439927Y-326359D01*
X440551Y-326483D01*
X441176Y-326359D01*
X441705Y-326006D01*
X442058Y-325476D01*
X442182Y-324852D01*
X442058Y-324228D01*
X441705Y-323698D01*
X441176Y-323345D01*
X440551Y-323221D01*
D02*
G37*
G36*
X433858D02*
X433234Y-323345D01*
X432705Y-323698D01*
X432256D01*
X431727Y-323345D01*
X431102Y-323221D01*
X430478Y-323345D01*
X429949Y-323698D01*
X429595Y-324228D01*
X429471Y-324852D01*
X429595Y-325476D01*
X429949Y-326006D01*
X430478Y-326359D01*
X431102Y-326483D01*
X431727Y-326359D01*
X432256Y-326006D01*
X432705D01*
X433234Y-326359D01*
X433858Y-326483D01*
X434483Y-326359D01*
X435012Y-326006D01*
X435365Y-325476D01*
X435490Y-324852D01*
X435365Y-324228D01*
X435012Y-323698D01*
X434483Y-323345D01*
X433858Y-323221D01*
D02*
G37*
G36*
X460630D02*
X460006Y-323345D01*
X459476Y-323698D01*
X459356Y-323879D01*
X458754D01*
X458634Y-323698D01*
X458105Y-323345D01*
X457480Y-323221D01*
X456856Y-323345D01*
X456327Y-323698D01*
X455973Y-324228D01*
X455964Y-324276D01*
X455454D01*
X455444Y-324228D01*
X455091Y-323698D01*
X454561Y-323345D01*
X453937Y-323221D01*
X453313Y-323345D01*
X452783Y-323698D01*
X452335D01*
X451805Y-323345D01*
X451181Y-323221D01*
X450557Y-323345D01*
X450028Y-323698D01*
X449674Y-324228D01*
X449550Y-324852D01*
X449674Y-325476D01*
X450028Y-326006D01*
X450557Y-326359D01*
X451181Y-326483D01*
X451805Y-326359D01*
X452335Y-326006D01*
X452783D01*
X453313Y-326359D01*
X453937Y-326483D01*
X454561Y-326359D01*
X455091Y-326006D01*
X455444Y-325476D01*
X455454Y-325428D01*
X455964D01*
X455973Y-325476D01*
X456327Y-326006D01*
X456856Y-326359D01*
X457480Y-326483D01*
X458105Y-326359D01*
X458634Y-326006D01*
X458754Y-325825D01*
X459356D01*
X459476Y-326006D01*
X460006Y-326359D01*
X460630Y-326483D01*
X461254Y-326359D01*
X461784Y-326006D01*
X462137Y-325476D01*
X462261Y-324852D01*
X462137Y-324228D01*
X461784Y-323698D01*
X461254Y-323345D01*
X460630Y-323221D01*
D02*
G37*
G36*
X87598Y-328093D02*
X86974Y-328217D01*
X86445Y-328571D01*
X86091Y-329100D01*
X85967Y-329724D01*
X86091Y-330349D01*
X86445Y-330878D01*
X86974Y-331232D01*
X87598Y-331356D01*
X88223Y-331232D01*
X88752Y-330878D01*
X89106Y-330349D01*
X89230Y-329724D01*
X89106Y-329100D01*
X88752Y-328571D01*
X88223Y-328217D01*
X87598Y-328093D01*
D02*
G37*
G36*
X62992D02*
X62368Y-328217D01*
X61839Y-328571D01*
X61485Y-329100D01*
X61361Y-329724D01*
X61485Y-330349D01*
X61839Y-330878D01*
X62368Y-331232D01*
X62992Y-331356D01*
X63616Y-331232D01*
X64146Y-330878D01*
X64499Y-330349D01*
X64623Y-329724D01*
X64499Y-329100D01*
X64146Y-328571D01*
X63616Y-328217D01*
X62992Y-328093D01*
D02*
G37*
G36*
X294094Y-322576D02*
X292907Y-322732D01*
X291800Y-323191D01*
X290849Y-323920D01*
X290120Y-324871D01*
X289662Y-325978D01*
X289505Y-327165D01*
X289662Y-328353D01*
X290120Y-329460D01*
X290849Y-330410D01*
X291800Y-331140D01*
X292907Y-331598D01*
X294094Y-331755D01*
X295282Y-331598D01*
X296389Y-331140D01*
X297340Y-330410D01*
X298069Y-329460D01*
X298527Y-328353D01*
X298684Y-327165D01*
X298527Y-325978D01*
X298069Y-324871D01*
X297340Y-323920D01*
X296389Y-323191D01*
X295282Y-322732D01*
X294094Y-322576D01*
D02*
G37*
G36*
X282283D02*
X281096Y-322732D01*
X279989Y-323191D01*
X279038Y-323920D01*
X278309Y-324871D01*
X277851Y-325978D01*
X277694Y-327165D01*
X277851Y-328353D01*
X278309Y-329460D01*
X279038Y-330410D01*
X279989Y-331140D01*
X281096Y-331598D01*
X282283Y-331755D01*
X283471Y-331598D01*
X284578Y-331140D01*
X285529Y-330410D01*
X286258Y-329460D01*
X286716Y-328353D01*
X286873Y-327165D01*
X286716Y-325978D01*
X286258Y-324871D01*
X285529Y-323920D01*
X284578Y-323191D01*
X283471Y-322732D01*
X282283Y-322576D01*
D02*
G37*
G36*
X270472D02*
X269285Y-322732D01*
X268178Y-323191D01*
X267227Y-323920D01*
X266498Y-324871D01*
X266040Y-325978D01*
X265883Y-327165D01*
X266040Y-328353D01*
X266498Y-329460D01*
X267227Y-330410D01*
X268178Y-331140D01*
X269285Y-331598D01*
X270472Y-331755D01*
X271660Y-331598D01*
X272767Y-331140D01*
X273717Y-330410D01*
X274447Y-329460D01*
X274905Y-328353D01*
X275062Y-327165D01*
X274905Y-325978D01*
X274447Y-324871D01*
X273717Y-323920D01*
X272767Y-323191D01*
X271660Y-322732D01*
X270472Y-322576D01*
D02*
G37*
G36*
X258472D02*
X257285Y-322732D01*
X256178Y-323191D01*
X255227Y-323920D01*
X254498Y-324871D01*
X254040Y-325978D01*
X253883Y-327165D01*
X254040Y-328353D01*
X254498Y-329460D01*
X255227Y-330410D01*
X256178Y-331140D01*
X257285Y-331598D01*
X258472Y-331755D01*
X259660Y-331598D01*
X260767Y-331140D01*
X261718Y-330410D01*
X262447Y-329460D01*
X262905Y-328353D01*
X263062Y-327165D01*
X262905Y-325978D01*
X262447Y-324871D01*
X261718Y-323920D01*
X260767Y-323191D01*
X259660Y-322732D01*
X258472Y-322576D01*
D02*
G37*
G36*
X246472D02*
X245285Y-322732D01*
X244178Y-323191D01*
X243227Y-323920D01*
X242498Y-324871D01*
X242040Y-325978D01*
X241883Y-327165D01*
X242040Y-328353D01*
X242498Y-329460D01*
X243227Y-330410D01*
X244178Y-331140D01*
X245285Y-331598D01*
X246472Y-331755D01*
X247660Y-331598D01*
X248767Y-331140D01*
X249717Y-330410D01*
X250447Y-329460D01*
X250905Y-328353D01*
X251062Y-327165D01*
X250905Y-325978D01*
X250447Y-324871D01*
X249717Y-323920D01*
X248767Y-323191D01*
X247660Y-322732D01*
X246472Y-322576D01*
D02*
G37*
G36*
X604291Y-325905D02*
X603221Y-326046D01*
X602224Y-326459D01*
X601368Y-327116D01*
X600711Y-327972D01*
X600298Y-328969D01*
X600157Y-330039D01*
X600298Y-331109D01*
X600711Y-332107D01*
X601368Y-332963D01*
X602224Y-333620D01*
X603221Y-334033D01*
X604291Y-334174D01*
X605361Y-334033D01*
X606359Y-333620D01*
X607215Y-332963D01*
X607872Y-332107D01*
X608285Y-331109D01*
X608426Y-330039D01*
X608285Y-328969D01*
X607872Y-327972D01*
X607215Y-327116D01*
X606359Y-326459D01*
X605361Y-326046D01*
X604291Y-325905D01*
D02*
G37*
G36*
X574291D02*
X573221Y-326046D01*
X572224Y-326459D01*
X571368Y-327116D01*
X570711Y-327972D01*
X570298Y-328969D01*
X570157Y-330039D01*
X570298Y-331109D01*
X570711Y-332107D01*
X571368Y-332963D01*
X572224Y-333620D01*
X573221Y-334033D01*
X574291Y-334174D01*
X575361Y-334033D01*
X576359Y-333620D01*
X577215Y-332963D01*
X577872Y-332107D01*
X578285Y-331109D01*
X578426Y-330039D01*
X578285Y-328969D01*
X577872Y-327972D01*
X577215Y-327116D01*
X576359Y-326459D01*
X575361Y-326046D01*
X574291Y-325905D01*
D02*
G37*
G36*
X87598Y-333999D02*
X86974Y-334123D01*
X86445Y-334476D01*
X86091Y-335006D01*
X85967Y-335630D01*
X86091Y-336254D01*
X86445Y-336784D01*
X86974Y-337137D01*
X87598Y-337261D01*
X88223Y-337137D01*
X88752Y-336784D01*
X89106Y-336254D01*
X89230Y-335630D01*
X89106Y-335006D01*
X88752Y-334476D01*
X88223Y-334123D01*
X87598Y-333999D01*
D02*
G37*
G36*
X-23622D02*
X-24246Y-334123D01*
X-24776Y-334476D01*
X-25129Y-335006D01*
X-25253Y-335630D01*
X-25129Y-336254D01*
X-24776Y-336784D01*
X-24246Y-337137D01*
X-23622Y-337261D01*
X-22998Y-337137D01*
X-22468Y-336784D01*
X-22115Y-336254D01*
X-21991Y-335630D01*
X-22115Y-335006D01*
X-22468Y-334476D01*
X-22998Y-334123D01*
X-23622Y-333999D01*
D02*
G37*
G36*
X508997Y-334044D02*
X508373Y-334168D01*
X507843Y-334521D01*
X507490Y-335051D01*
X507366Y-335675D01*
X507490Y-336299D01*
X507843Y-336828D01*
X508373Y-337182D01*
X508997Y-337306D01*
X509621Y-337182D01*
X510151Y-336828D01*
X510504Y-336299D01*
X510628Y-335675D01*
X510504Y-335051D01*
X510151Y-334521D01*
X509621Y-334168D01*
X508997Y-334044D01*
D02*
G37*
G36*
X74803Y-337936D02*
X74179Y-338060D01*
X73650Y-338413D01*
X73296Y-338943D01*
X73172Y-339567D01*
X73296Y-340191D01*
X73650Y-340721D01*
X74179Y-341074D01*
X74803Y-341198D01*
X75427Y-341074D01*
X75957Y-340721D01*
X76310Y-340191D01*
X76434Y-339567D01*
X76310Y-338943D01*
X75957Y-338413D01*
X75427Y-338060D01*
X74803Y-337936D01*
D02*
G37*
G36*
X78740Y-338920D02*
X78116Y-339044D01*
X77587Y-339398D01*
X77233Y-339927D01*
X77109Y-340551D01*
X77233Y-341176D01*
X77587Y-341705D01*
X78116Y-342058D01*
X78740Y-342182D01*
X79364Y-342058D01*
X79894Y-341705D01*
X80247Y-341176D01*
X80371Y-340551D01*
X80247Y-339927D01*
X79894Y-339398D01*
X79364Y-339044D01*
X78740Y-338920D01*
D02*
G37*
G36*
X-23622Y-337936D02*
X-24246Y-338060D01*
X-24776Y-338413D01*
X-25129Y-338943D01*
X-25253Y-339567D01*
X-25129Y-340191D01*
X-24776Y-340721D01*
X-24667Y-340793D01*
Y-341293D01*
X-24776Y-341366D01*
X-25129Y-341895D01*
X-25253Y-342520D01*
X-25129Y-343144D01*
X-24776Y-343673D01*
X-24246Y-344027D01*
X-23622Y-344151D01*
X-22998Y-344027D01*
X-22468Y-343673D01*
X-22115Y-343144D01*
X-21991Y-342520D01*
X-22115Y-341895D01*
X-22468Y-341366D01*
X-22578Y-341293D01*
Y-340793D01*
X-22468Y-340721D01*
X-22115Y-340191D01*
X-21991Y-339567D01*
X-22115Y-338943D01*
X-22468Y-338413D01*
X-22998Y-338060D01*
X-23622Y-337936D01*
D02*
G37*
G36*
Y-344825D02*
X-24246Y-344950D01*
X-24776Y-345303D01*
X-25129Y-345832D01*
X-25253Y-346457D01*
X-25129Y-347081D01*
X-24776Y-347610D01*
X-24246Y-347964D01*
X-23622Y-348088D01*
X-22998Y-347964D01*
X-22468Y-347610D01*
X-22115Y-347081D01*
X-21991Y-346457D01*
X-22115Y-345832D01*
X-22468Y-345303D01*
X-22998Y-344950D01*
X-23622Y-344825D01*
D02*
G37*
G36*
X509391Y-349004D02*
X508767Y-349128D01*
X508237Y-349482D01*
X507884Y-350011D01*
X507759Y-350636D01*
X507884Y-351260D01*
X508237Y-351789D01*
X508767Y-352143D01*
X509391Y-352267D01*
X510015Y-352143D01*
X510544Y-351789D01*
X510898Y-351260D01*
X511022Y-350636D01*
X510898Y-350011D01*
X510544Y-349482D01*
X510015Y-349128D01*
X509391Y-349004D01*
D02*
G37*
G36*
X486221Y-327210D02*
X484133Y-327374D01*
X482098Y-327863D01*
X480164Y-328664D01*
X478379Y-329758D01*
X476787Y-331118D01*
X475427Y-332710D01*
X474333Y-334494D01*
X473532Y-336428D01*
X473044Y-338464D01*
X472879Y-340551D01*
X473044Y-342638D01*
X473532Y-344674D01*
X474333Y-346608D01*
X475427Y-348393D01*
X476787Y-349985D01*
X478379Y-351344D01*
X480164Y-352438D01*
X482098Y-353239D01*
X484133Y-353728D01*
X486221Y-353892D01*
X488308Y-353728D01*
X490343Y-353239D01*
X492277Y-352438D01*
X494062Y-351344D01*
X495654Y-349985D01*
X497014Y-348393D01*
X498107Y-346608D01*
X498909Y-344674D01*
X499397Y-342638D01*
X499562Y-340551D01*
X499397Y-338464D01*
X498909Y-336428D01*
X498107Y-334494D01*
X497014Y-332710D01*
X495654Y-331118D01*
X494062Y-329758D01*
X492277Y-328664D01*
X490343Y-327863D01*
X488308Y-327374D01*
X486221Y-327210D01*
D02*
G37*
G36*
X685039Y-327210D02*
X682952Y-327374D01*
X680917Y-327863D01*
X678983Y-328664D01*
X677198Y-329758D01*
X675606Y-331118D01*
X674246Y-332710D01*
X673152Y-334494D01*
X672351Y-336429D01*
X671863Y-338464D01*
X671698Y-340551D01*
X671863Y-342638D01*
X672351Y-344674D01*
X673152Y-346608D01*
X674246Y-348393D01*
X675606Y-349985D01*
X677198Y-351344D01*
X678983Y-352438D01*
X680917Y-353239D01*
X682952Y-353728D01*
X685039Y-353892D01*
X687126Y-353728D01*
X689162Y-353239D01*
X691096Y-352438D01*
X692881Y-351344D01*
X694473Y-349985D01*
X695833Y-348393D01*
X696926Y-346608D01*
X697727Y-344674D01*
X698216Y-342638D01*
X698381Y-340551D01*
X698216Y-338464D01*
X697727Y-336429D01*
X696926Y-334494D01*
X695833Y-332710D01*
X694473Y-331118D01*
X692881Y-329758D01*
X691096Y-328664D01*
X689162Y-327863D01*
X687126Y-327374D01*
X685039Y-327210D01*
D02*
G37*
G36*
X157480Y-357030D02*
X156856Y-357154D01*
X156496Y-357395D01*
X156136Y-357154D01*
X155512Y-357030D01*
X154887Y-357154D01*
X154528Y-357395D01*
X154168Y-357154D01*
X153543Y-357030D01*
X152919Y-357154D01*
X152390Y-357508D01*
X152036Y-358037D01*
X151912Y-358661D01*
X152036Y-359286D01*
X152390Y-359815D01*
X152570Y-359936D01*
Y-360537D01*
X152390Y-360658D01*
X152036Y-361187D01*
X151912Y-361811D01*
X152036Y-362435D01*
X152390Y-362965D01*
X152919Y-363318D01*
X153543Y-363442D01*
X154168Y-363318D01*
X154528Y-363078D01*
X154887Y-363318D01*
X155512Y-363442D01*
X156136Y-363318D01*
X156496Y-363078D01*
X156856Y-363318D01*
X157480Y-363442D01*
X158105Y-363318D01*
X158634Y-362965D01*
X158987Y-362435D01*
X159112Y-361811D01*
X158987Y-361187D01*
X158634Y-360658D01*
X158453Y-360537D01*
Y-359936D01*
X158634Y-359815D01*
X158987Y-359286D01*
X159112Y-358661D01*
X158987Y-358037D01*
X158634Y-357508D01*
X158105Y-357154D01*
X157480Y-357030D01*
D02*
G37*
G36*
X218445Y-372476D02*
X217821Y-372600D01*
X217291Y-372954D01*
X216938Y-373483D01*
X216814Y-374108D01*
X216938Y-374732D01*
X217291Y-375261D01*
X217821Y-375615D01*
X218445Y-375739D01*
X219069Y-375615D01*
X219599Y-375261D01*
X219952Y-374732D01*
X220076Y-374108D01*
X219952Y-373483D01*
X219599Y-372954D01*
X219069Y-372600D01*
X218445Y-372476D01*
D02*
G37*
G36*
X269502Y-372660D02*
X268878Y-372784D01*
X268349Y-373137D01*
X267995Y-373667D01*
X267871Y-374291D01*
X267995Y-374915D01*
X268349Y-375445D01*
X268878Y-375798D01*
X269502Y-375922D01*
X270127Y-375798D01*
X270656Y-375445D01*
X271010Y-374915D01*
X271134Y-374291D01*
X271010Y-373667D01*
X270656Y-373137D01*
X270127Y-372784D01*
X269502Y-372660D01*
D02*
G37*
G36*
X273425Y-373024D02*
X272801Y-373148D01*
X272272Y-373502D01*
X271918Y-374031D01*
X271794Y-374655D01*
X271918Y-375279D01*
X272272Y-375809D01*
X272801Y-376162D01*
X273425Y-376287D01*
X274049Y-376162D01*
X274579Y-375809D01*
X274932Y-375279D01*
X275057Y-374655D01*
X274932Y-374031D01*
X274579Y-373502D01*
X274049Y-373148D01*
X273425Y-373024D01*
D02*
G37*
G36*
X253655Y-372790D02*
X253031Y-372914D01*
X252502Y-373268D01*
X252148Y-373797D01*
X252024Y-374421D01*
X252148Y-375045D01*
X252502Y-375575D01*
X253031Y-375928D01*
X253655Y-376052D01*
X254279Y-375928D01*
X254809Y-375575D01*
X254916Y-375413D01*
X254985Y-375394D01*
X255495Y-375448D01*
X255736Y-375809D01*
X256265Y-376162D01*
X256890Y-376287D01*
X257514Y-376162D01*
X258043Y-375809D01*
X258397Y-375279D01*
X258521Y-374655D01*
X258397Y-374031D01*
X258043Y-373502D01*
X257514Y-373148D01*
X256890Y-373024D01*
X256265Y-373148D01*
X255736Y-373502D01*
X255628Y-373663D01*
X255560Y-373683D01*
X255050Y-373629D01*
X254809Y-373268D01*
X254279Y-372914D01*
X253655Y-372790D01*
D02*
G37*
G36*
X241929Y-373024D02*
X241305Y-373148D01*
X240776Y-373502D01*
X240422Y-374031D01*
X240298Y-374655D01*
X240422Y-375279D01*
X240776Y-375809D01*
X241305Y-376162D01*
X241929Y-376287D01*
X242553Y-376162D01*
X243083Y-375809D01*
X243436Y-375279D01*
X243561Y-374655D01*
X243436Y-374031D01*
X243083Y-373502D01*
X242553Y-373148D01*
X241929Y-373024D01*
D02*
G37*
G36*
X237992D02*
X237368Y-373148D01*
X236839Y-373502D01*
X236485Y-374031D01*
X236361Y-374655D01*
X236485Y-375279D01*
X236839Y-375809D01*
X237368Y-376162D01*
X237992Y-376287D01*
X238616Y-376162D01*
X239146Y-375809D01*
X239499Y-375279D01*
X239623Y-374655D01*
X239499Y-374031D01*
X239146Y-373502D01*
X238616Y-373148D01*
X237992Y-373024D01*
D02*
G37*
G36*
X222638D02*
X222013Y-373148D01*
X221484Y-373502D01*
X221131Y-374031D01*
X221006Y-374655D01*
X221131Y-375279D01*
X221484Y-375809D01*
X222013Y-376162D01*
X222638Y-376287D01*
X223262Y-376162D01*
X223791Y-375809D01*
X224145Y-375279D01*
X224269Y-374655D01*
X224145Y-374031D01*
X223791Y-373502D01*
X223262Y-373148D01*
X222638Y-373024D01*
D02*
G37*
G36*
X210433D02*
X209809Y-373148D01*
X209279Y-373502D01*
X208926Y-374031D01*
X208802Y-374655D01*
X208926Y-375279D01*
X209279Y-375809D01*
X209809Y-376162D01*
X210433Y-376287D01*
X211057Y-376162D01*
X211587Y-375809D01*
X211940Y-375279D01*
X212064Y-374655D01*
X211940Y-374031D01*
X211587Y-373502D01*
X211057Y-373148D01*
X210433Y-373024D01*
D02*
G37*
G36*
X206496D02*
X205872Y-373148D01*
X205343Y-373502D01*
X204989Y-374031D01*
X204865Y-374655D01*
X204989Y-375279D01*
X205343Y-375809D01*
X205872Y-376162D01*
X206496Y-376287D01*
X207120Y-376162D01*
X207650Y-375809D01*
X208003Y-375279D01*
X208127Y-374655D01*
X208003Y-374031D01*
X207650Y-373502D01*
X207120Y-373148D01*
X206496Y-373024D01*
D02*
G37*
G36*
X190354Y-375780D02*
X189730Y-375904D01*
X189201Y-376257D01*
X188847Y-376787D01*
X188723Y-377411D01*
X188847Y-378035D01*
X189201Y-378565D01*
X189730Y-378918D01*
X190354Y-379042D01*
X190979Y-378918D01*
X191508Y-378565D01*
X191861Y-378035D01*
X191986Y-377411D01*
X191861Y-376787D01*
X191508Y-376257D01*
X190979Y-375904D01*
X190354Y-375780D01*
D02*
G37*
G36*
X178543D02*
X177919Y-375904D01*
X177390Y-376257D01*
X177036Y-376787D01*
X176912Y-377411D01*
X177036Y-378035D01*
X177390Y-378565D01*
X177919Y-378918D01*
X178543Y-379042D01*
X179168Y-378918D01*
X179697Y-378565D01*
X180051Y-378035D01*
X180175Y-377411D01*
X180051Y-376787D01*
X179697Y-376257D01*
X179168Y-375904D01*
X178543Y-375780D01*
D02*
G37*
G36*
X158661Y-384835D02*
X158037Y-384959D01*
X157677Y-385199D01*
X157317Y-384959D01*
X156693Y-384835D01*
X156069Y-384959D01*
X155709Y-385199D01*
X155349Y-384959D01*
X154724Y-384835D01*
X154100Y-384959D01*
X153571Y-385313D01*
X153217Y-385842D01*
X153093Y-386466D01*
X153217Y-387090D01*
X153571Y-387620D01*
X153751Y-387740D01*
Y-388342D01*
X153571Y-388462D01*
X153217Y-388991D01*
X153093Y-389616D01*
X153217Y-390240D01*
X153571Y-390769D01*
X154100Y-391123D01*
X154724Y-391247D01*
X155349Y-391123D01*
X155709Y-390882D01*
X156069Y-391123D01*
X156693Y-391247D01*
X157317Y-391123D01*
X157677Y-390882D01*
X158037Y-391123D01*
X158661Y-391247D01*
X159286Y-391123D01*
X159815Y-390769D01*
X160169Y-390240D01*
X160293Y-389616D01*
X160169Y-388991D01*
X159815Y-388462D01*
X159634Y-388342D01*
Y-387740D01*
X159815Y-387620D01*
X160169Y-387090D01*
X160293Y-386466D01*
X160169Y-385842D01*
X159815Y-385313D01*
X159286Y-384959D01*
X158661Y-384835D01*
D02*
G37*
G36*
X182677D02*
X182053Y-384959D01*
X181524Y-385313D01*
X181170Y-385842D01*
X181160Y-385890D01*
X180651D01*
X180641Y-385842D01*
X180287Y-385313D01*
X179758Y-384959D01*
X179134Y-384835D01*
X178510Y-384959D01*
X177980Y-385313D01*
X177627Y-385842D01*
X177503Y-386466D01*
X177627Y-387090D01*
X177980Y-387620D01*
X178161Y-387740D01*
Y-388342D01*
X177980Y-388462D01*
X177627Y-388991D01*
X177503Y-389616D01*
X177627Y-390240D01*
X177980Y-390769D01*
X178510Y-391123D01*
X179134Y-391247D01*
X179758Y-391123D01*
X180287Y-390769D01*
X180641Y-390240D01*
X180651Y-390192D01*
X181160D01*
X181170Y-390240D01*
X181524Y-390769D01*
X182053Y-391123D01*
X182677Y-391247D01*
X183301Y-391123D01*
X183831Y-390769D01*
X184184Y-390240D01*
X184309Y-389616D01*
X184184Y-388991D01*
X183831Y-388462D01*
X183650Y-388342D01*
Y-387740D01*
X183831Y-387620D01*
X184184Y-387090D01*
X184309Y-386466D01*
X184184Y-385842D01*
X183831Y-385313D01*
X183301Y-384959D01*
X182677Y-384835D01*
D02*
G37*
G36*
X232480Y-385622D02*
X231856Y-385746D01*
X231327Y-386100D01*
X231206Y-386280D01*
X230605D01*
X230484Y-386100D01*
X229955Y-385746D01*
X229331Y-385622D01*
X228706Y-385746D01*
X228177Y-386100D01*
X227823Y-386629D01*
X227699Y-387253D01*
X227823Y-387878D01*
X228177Y-388407D01*
X228706Y-388761D01*
X229331Y-388885D01*
X229955Y-388761D01*
X230484Y-388407D01*
X230605Y-388227D01*
X231206D01*
X231327Y-388407D01*
X231856Y-388761D01*
X232480Y-388885D01*
X233105Y-388761D01*
X233634Y-388407D01*
X233987Y-387878D01*
X234112Y-387253D01*
X233987Y-386629D01*
X233634Y-386100D01*
X233105Y-385746D01*
X232480Y-385622D01*
D02*
G37*
G36*
X215945D02*
X215321Y-385746D01*
X214791Y-386100D01*
X214671Y-386280D01*
X214069D01*
X213949Y-386100D01*
X213420Y-385746D01*
X212795Y-385622D01*
X212171Y-385746D01*
X211642Y-386100D01*
X211288Y-386629D01*
X211164Y-387253D01*
X211288Y-387878D01*
X211642Y-388407D01*
X212171Y-388761D01*
X212795Y-388885D01*
X213420Y-388761D01*
X213949Y-388407D01*
X214069Y-388227D01*
X214671D01*
X214791Y-388407D01*
X215321Y-388761D01*
X215945Y-388885D01*
X216569Y-388761D01*
X217098Y-388407D01*
X217452Y-387878D01*
X217576Y-387253D01*
X217452Y-386629D01*
X217098Y-386100D01*
X216569Y-385746D01*
X215945Y-385622D01*
D02*
G37*
G36*
X265158D02*
X264533Y-385746D01*
X264004Y-386100D01*
X263882Y-386283D01*
X263281D01*
X263160Y-386102D01*
X262631Y-385748D01*
X262006Y-385624D01*
X261382Y-385748D01*
X260853Y-386102D01*
X260499Y-386631D01*
X260375Y-387255D01*
X260499Y-387880D01*
X260853Y-388409D01*
X261382Y-388762D01*
X262006Y-388887D01*
X262631Y-388762D01*
X263160Y-388409D01*
X263282Y-388226D01*
X263883D01*
X264004Y-388407D01*
X264533Y-388761D01*
X265158Y-388885D01*
X265782Y-388761D01*
X266311Y-388407D01*
X266665Y-387878D01*
X266789Y-387253D01*
X266665Y-386629D01*
X266311Y-386100D01*
X265782Y-385746D01*
X265158Y-385622D01*
D02*
G37*
G36*
X246339Y-385344D02*
X245714Y-385468D01*
X245185Y-385822D01*
X244831Y-386351D01*
X244707Y-386975D01*
X244831Y-387599D01*
X245185Y-388129D01*
X245714Y-388482D01*
X246339Y-388606D01*
X246963Y-388482D01*
X247492Y-388129D01*
X248082Y-388146D01*
X248256Y-388407D01*
X248785Y-388761D01*
X249410Y-388885D01*
X250034Y-388761D01*
X250563Y-388407D01*
X250917Y-387878D01*
X251041Y-387253D01*
X250917Y-386629D01*
X250563Y-386100D01*
X250034Y-385746D01*
X249410Y-385622D01*
X248785Y-385746D01*
X248256Y-386100D01*
X247666Y-386082D01*
X247492Y-385822D01*
X246963Y-385468D01*
X246339Y-385344D01*
D02*
G37*
G36*
X186614Y-384835D02*
X185990Y-384959D01*
X185461Y-385313D01*
X185107Y-385842D01*
X184983Y-386466D01*
X185107Y-387090D01*
X185461Y-387620D01*
X185641Y-387740D01*
Y-388342D01*
X185461Y-388462D01*
X185107Y-388991D01*
X184983Y-389616D01*
X185107Y-390240D01*
X185461Y-390769D01*
X185990Y-391123D01*
X186614Y-391247D01*
X187239Y-391123D01*
X187768Y-390769D01*
X188121Y-390240D01*
X188245Y-389616D01*
X188121Y-388991D01*
X187768Y-388462D01*
X187587Y-388342D01*
Y-387740D01*
X187768Y-387620D01*
X188121Y-387090D01*
X188245Y-386466D01*
X188121Y-385842D01*
X187768Y-385313D01*
X187239Y-384959D01*
X186614Y-384835D01*
D02*
G37*
G36*
X0Y-365054D02*
X-2087Y-365218D01*
X-4123Y-365707D01*
X-6057Y-366508D01*
X-7842Y-367602D01*
X-9434Y-368962D01*
X-10793Y-370554D01*
X-11887Y-372339D01*
X-12688Y-374273D01*
X-13177Y-376308D01*
X-13341Y-378395D01*
X-13177Y-380482D01*
X-12688Y-382518D01*
X-11887Y-384452D01*
X-10793Y-386237D01*
X-9434Y-387829D01*
X-7842Y-389189D01*
X-6057Y-390282D01*
X-4123Y-391083D01*
X-2087Y-391572D01*
X0Y-391736D01*
X2087Y-391572D01*
X4123Y-391083D01*
X6057Y-390282D01*
X7842Y-389189D01*
X9434Y-387829D01*
X10793Y-386237D01*
X11887Y-384452D01*
X12688Y-382518D01*
X13177Y-380482D01*
X13341Y-378395D01*
X13177Y-376308D01*
X12688Y-374273D01*
X11887Y-372339D01*
X10793Y-370554D01*
X9434Y-368962D01*
X7842Y-367602D01*
X6057Y-366508D01*
X4123Y-365707D01*
X2087Y-365218D01*
X0Y-365054D01*
D02*
G37*
%LPD*%
D157*
X162362Y-120079D02*
D03*
X549055Y13937D02*
D03*
Y3937D02*
D03*
D159*
X302362Y-316535D02*
D03*
X142520Y-236614D02*
D03*
D160*
X348211Y-89891D02*
D03*
X357798Y-89963D02*
D03*
D161*
X624016Y-194488D02*
D03*
Y-177953D02*
D03*
Y-161417D02*
D03*
D164*
X-18464Y-326781D02*
D03*
X1535D02*
D03*
Y-306781D02*
D03*
X-18464D02*
D03*
X-18465Y-273630D02*
D03*
X1535D02*
D03*
Y-253630D02*
D03*
X-18465D02*
D03*
Y-220480D02*
D03*
X1535D02*
D03*
Y-200480D02*
D03*
X-18465D02*
D03*
X-18464Y-167332D02*
D03*
X1535D02*
D03*
Y-147332D02*
D03*
X-18464D02*
D03*
D167*
X315097Y-235081D02*
D03*
X287941Y-241819D02*
D03*
X288189Y-235827D02*
D03*
X615748Y-305512D02*
D03*
X562598Y-306693D02*
D03*
X600000Y-146063D02*
D03*
X598032D02*
D03*
X596063D02*
D03*
X587008D02*
D03*
X585039D02*
D03*
X583071D02*
D03*
X575984Y-145669D02*
D03*
X574016D02*
D03*
X572047D02*
D03*
X650787Y-229921D02*
D03*
X645669Y-230315D02*
D03*
X641732D02*
D03*
X638189D02*
D03*
X575919Y-236906D02*
D03*
X596702Y-247441D02*
D03*
X591978D02*
D03*
X586466D02*
D03*
X580954Y-207189D02*
D03*
X580935Y-237412D02*
D03*
X554519Y-212889D02*
D03*
X546419Y-246106D02*
D03*
X626819Y-244005D02*
D03*
X611094Y-248110D02*
D03*
X603002Y-247441D02*
D03*
X531496Y-262647D02*
D03*
X461811Y-310679D02*
D03*
X450000Y-293750D02*
D03*
X422441Y-293789D02*
D03*
X531496Y-213435D02*
D03*
X338525Y-243567D02*
D03*
X525591Y-233088D02*
D03*
X439697Y-162549D02*
D03*
X343144Y-225173D02*
D03*
X420669Y-157923D02*
D03*
X531496Y-223277D02*
D03*
X338583Y-235236D02*
D03*
X525591Y-242962D02*
D03*
X430150Y-162253D02*
D03*
X343444Y-215373D02*
D03*
X432283Y-293750D02*
D03*
X410528Y-157923D02*
D03*
X342944Y-264473D02*
D03*
X444095Y-293750D02*
D03*
X422835Y-311072D02*
D03*
X531496Y-233088D02*
D03*
X430150Y-157923D02*
D03*
X338444Y-225173D02*
D03*
X402756Y-311072D02*
D03*
X525591Y-253969D02*
D03*
X420079Y-162549D02*
D03*
X343403Y-205651D02*
D03*
X525591Y-203592D02*
D03*
X400295Y-157824D02*
D03*
X343144Y-254773D02*
D03*
X431928Y-311189D02*
D03*
X531496Y-242962D02*
D03*
X338844Y-215273D02*
D03*
X402362Y-293750D02*
D03*
X525591Y-262647D02*
D03*
X410913Y-162758D02*
D03*
X338444Y-264473D02*
D03*
X456299Y-293750D02*
D03*
X437795Y-293750D02*
D03*
X525591Y-213435D02*
D03*
X459319Y-162510D02*
D03*
Y-157922D02*
D03*
X342744Y-243747D02*
D03*
X412598Y-311072D02*
D03*
X531496Y-253969D02*
D03*
X449803Y-157923D02*
D03*
X338744Y-205473D02*
D03*
X531496Y-203592D02*
D03*
X401279Y-162509D02*
D03*
X439961Y-157923D02*
D03*
X338444Y-254773D02*
D03*
X461417Y-293750D02*
D03*
X525591Y-223277D02*
D03*
X449508Y-162549D02*
D03*
X343504Y-235236D02*
D03*
X412205Y-293750D02*
D03*
X639750Y-314581D02*
D03*
X658647Y-314581D02*
D03*
X509405Y-345138D02*
D03*
X509011Y-330177D02*
D03*
X56441Y-143600D02*
D03*
Y-151600D02*
D03*
Y-191600D02*
D03*
Y-199600D02*
D03*
Y-215600D02*
D03*
Y-223600D02*
D03*
Y-231600D02*
D03*
Y-247600D02*
D03*
Y-255600D02*
D03*
Y-271600D02*
D03*
Y-279600D02*
D03*
Y-287600D02*
D03*
Y-303600D02*
D03*
Y-311600D02*
D03*
Y-327600D02*
D03*
Y-335600D02*
D03*
Y-343600D02*
D03*
Y-351600D02*
D03*
X54441Y-139600D02*
D03*
X52441Y-143600D02*
D03*
X54441Y-147600D02*
D03*
X52441Y-151600D02*
D03*
Y-191600D02*
D03*
X54441Y-195600D02*
D03*
X52441Y-199600D02*
D03*
X54441Y-203600D02*
D03*
X52441Y-215600D02*
D03*
X54441Y-219600D02*
D03*
X52441Y-223600D02*
D03*
X54441Y-227600D02*
D03*
X52441Y-231600D02*
D03*
X54441Y-235600D02*
D03*
Y-243600D02*
D03*
X52441Y-247600D02*
D03*
X54441Y-251600D02*
D03*
X52441Y-255600D02*
D03*
X54441Y-267600D02*
D03*
X52441Y-271600D02*
D03*
X54441Y-275600D02*
D03*
X52441Y-279600D02*
D03*
Y-287600D02*
D03*
X54441Y-291600D02*
D03*
Y-299600D02*
D03*
X52441Y-303600D02*
D03*
X54441Y-307600D02*
D03*
X52441Y-311600D02*
D03*
X54441Y-323600D02*
D03*
X52441Y-327600D02*
D03*
X54441Y-331600D02*
D03*
X52441Y-335600D02*
D03*
X54441Y-339600D02*
D03*
X52441Y-343600D02*
D03*
Y-351600D02*
D03*
X50441Y-139600D02*
D03*
X48441Y-143600D02*
D03*
X50441Y-195600D02*
D03*
X48441Y-199600D02*
D03*
Y-223600D02*
D03*
X50441Y-227600D02*
D03*
X48441Y-231600D02*
D03*
X50441Y-235600D02*
D03*
Y-243600D02*
D03*
X48441Y-247600D02*
D03*
X50441Y-251600D02*
D03*
Y-275600D02*
D03*
X48441Y-279600D02*
D03*
Y-287600D02*
D03*
X50441Y-291600D02*
D03*
Y-299600D02*
D03*
X48441Y-303600D02*
D03*
X50441Y-331600D02*
D03*
X48441Y-335600D02*
D03*
X50441Y-339600D02*
D03*
X48441Y-343600D02*
D03*
Y-351600D02*
D03*
X46441Y-139600D02*
D03*
X44441Y-143600D02*
D03*
X46441Y-227600D02*
D03*
X44441Y-231600D02*
D03*
X46441Y-235600D02*
D03*
Y-243600D02*
D03*
X44441Y-247600D02*
D03*
Y-279600D02*
D03*
Y-287600D02*
D03*
X46441Y-291600D02*
D03*
Y-299600D02*
D03*
Y-331600D02*
D03*
X44441Y-335600D02*
D03*
X46441Y-339600D02*
D03*
X44441Y-343600D02*
D03*
Y-351600D02*
D03*
X42441Y-139600D02*
D03*
X40441Y-143600D02*
D03*
Y-223600D02*
D03*
X42441Y-227600D02*
D03*
X40441Y-231600D02*
D03*
X42441Y-235600D02*
D03*
Y-243600D02*
D03*
X40441Y-247600D02*
D03*
X42441Y-299600D02*
D03*
Y-331600D02*
D03*
X40441Y-335600D02*
D03*
X42441Y-339600D02*
D03*
X40441Y-343600D02*
D03*
Y-351600D02*
D03*
X38441Y-139600D02*
D03*
X36441Y-143600D02*
D03*
Y-151600D02*
D03*
Y-215600D02*
D03*
Y-223600D02*
D03*
X38441Y-227600D02*
D03*
X36441Y-231600D02*
D03*
X38441Y-235600D02*
D03*
Y-243600D02*
D03*
X36441Y-247600D02*
D03*
X38441Y-251600D02*
D03*
X36441Y-255600D02*
D03*
Y-327600D02*
D03*
X38441Y-331600D02*
D03*
X36441Y-335600D02*
D03*
X38441Y-339600D02*
D03*
X36441Y-343600D02*
D03*
Y-351600D02*
D03*
X34441Y-139600D02*
D03*
X32441Y-143600D02*
D03*
X34441Y-147600D02*
D03*
X32441Y-151600D02*
D03*
X34441Y-163600D02*
D03*
Y-219600D02*
D03*
Y-227600D02*
D03*
Y-235600D02*
D03*
Y-243600D02*
D03*
Y-251600D02*
D03*
Y-267600D02*
D03*
Y-275600D02*
D03*
Y-299600D02*
D03*
Y-307600D02*
D03*
Y-323600D02*
D03*
X32441Y-327600D02*
D03*
X34441Y-331600D02*
D03*
X32441Y-335600D02*
D03*
X34441Y-339600D02*
D03*
X32441Y-343600D02*
D03*
Y-351600D02*
D03*
X30441Y-139600D02*
D03*
X28441Y-143600D02*
D03*
X30441Y-147600D02*
D03*
X28441Y-151600D02*
D03*
X30441Y-163600D02*
D03*
X28441Y-167600D02*
D03*
Y-327600D02*
D03*
X30441Y-331600D02*
D03*
X28441Y-335600D02*
D03*
X30441Y-339600D02*
D03*
X28441Y-343600D02*
D03*
Y-351600D02*
D03*
X26441Y-139600D02*
D03*
X24441Y-143600D02*
D03*
X26441Y-147600D02*
D03*
X24441Y-151600D02*
D03*
X26441Y-163600D02*
D03*
X24441Y-167600D02*
D03*
Y-191600D02*
D03*
X26441Y-195600D02*
D03*
X24441Y-287600D02*
D03*
X26441Y-299600D02*
D03*
X24441Y-303600D02*
D03*
X26441Y-307600D02*
D03*
X24441Y-311600D02*
D03*
X26441Y-331600D02*
D03*
X24441Y-335600D02*
D03*
X26441Y-339600D02*
D03*
X24441Y-343600D02*
D03*
Y-351600D02*
D03*
X22441Y-139600D02*
D03*
X20441Y-143600D02*
D03*
X22441Y-147600D02*
D03*
X20441Y-151600D02*
D03*
X22441Y-163600D02*
D03*
X20441Y-167600D02*
D03*
X22441Y-171600D02*
D03*
X20441Y-191600D02*
D03*
X22441Y-195600D02*
D03*
X20441Y-199600D02*
D03*
Y-231600D02*
D03*
X22441Y-235600D02*
D03*
Y-243600D02*
D03*
X20441Y-247600D02*
D03*
X22441Y-251600D02*
D03*
X20441Y-255600D02*
D03*
X22441Y-259600D02*
D03*
Y-267600D02*
D03*
X20441Y-271600D02*
D03*
X22441Y-283600D02*
D03*
X20441Y-287600D02*
D03*
X22441Y-291600D02*
D03*
Y-299600D02*
D03*
X20441Y-303600D02*
D03*
X22441Y-307600D02*
D03*
X20441Y-311600D02*
D03*
X22441Y-323600D02*
D03*
X20441Y-335600D02*
D03*
X22441Y-339600D02*
D03*
X20441Y-343600D02*
D03*
Y-351600D02*
D03*
X18441Y-139600D02*
D03*
X16441Y-143600D02*
D03*
X18441Y-147600D02*
D03*
X16441Y-151600D02*
D03*
X18441Y-163600D02*
D03*
X16441Y-167600D02*
D03*
X18441Y-171600D02*
D03*
X16441Y-191600D02*
D03*
X18441Y-195600D02*
D03*
X16441Y-199600D02*
D03*
X18441Y-203600D02*
D03*
X16441Y-215600D02*
D03*
X18441Y-219600D02*
D03*
X16441Y-223600D02*
D03*
X18441Y-235600D02*
D03*
Y-243600D02*
D03*
X16441Y-247600D02*
D03*
X18441Y-251600D02*
D03*
X16441Y-255600D02*
D03*
X18441Y-259600D02*
D03*
Y-267600D02*
D03*
X16441Y-271600D02*
D03*
X18441Y-275600D02*
D03*
X16441Y-279600D02*
D03*
X18441Y-291600D02*
D03*
Y-299600D02*
D03*
X16441Y-303600D02*
D03*
X18441Y-307600D02*
D03*
X16441Y-311600D02*
D03*
X18441Y-323600D02*
D03*
X16441Y-327600D02*
D03*
X18441Y-339600D02*
D03*
X16441Y-343600D02*
D03*
Y-351600D02*
D03*
X14441Y-139600D02*
D03*
X12441Y-143600D02*
D03*
X14441Y-147600D02*
D03*
X12441Y-151600D02*
D03*
X14441Y-163600D02*
D03*
X12441Y-167600D02*
D03*
X14441Y-171600D02*
D03*
X12441Y-191600D02*
D03*
X14441Y-195600D02*
D03*
X12441Y-199600D02*
D03*
X14441Y-203600D02*
D03*
X12441Y-215600D02*
D03*
X14441Y-219600D02*
D03*
X12441Y-223600D02*
D03*
X14441Y-243600D02*
D03*
X12441Y-247600D02*
D03*
X14441Y-251600D02*
D03*
X12441Y-255600D02*
D03*
X14441Y-259600D02*
D03*
Y-267600D02*
D03*
X12441Y-271600D02*
D03*
X14441Y-275600D02*
D03*
X12441Y-279600D02*
D03*
X14441Y-291600D02*
D03*
Y-299600D02*
D03*
X12441Y-303600D02*
D03*
X14441Y-307600D02*
D03*
X12441Y-311600D02*
D03*
X14441Y-323600D02*
D03*
X12441Y-327600D02*
D03*
X14441Y-331600D02*
D03*
X12441Y-343600D02*
D03*
Y-351600D02*
D03*
X10441Y-139600D02*
D03*
Y-163600D02*
D03*
Y-171600D02*
D03*
X8441Y-191600D02*
D03*
X10441Y-195600D02*
D03*
Y-203600D02*
D03*
Y-227600D02*
D03*
Y-243600D02*
D03*
X8441Y-247600D02*
D03*
X10441Y-251600D02*
D03*
Y-259600D02*
D03*
Y-267600D02*
D03*
Y-275600D02*
D03*
X8441Y-279600D02*
D03*
X10441Y-299600D02*
D03*
Y-323600D02*
D03*
Y-331600D02*
D03*
X8441Y-351600D02*
D03*
X6441Y-139600D02*
D03*
X4441Y-191600D02*
D03*
X6441Y-243600D02*
D03*
X4441Y-351600D02*
D03*
X2441Y-243600D02*
D03*
X441Y-351600D02*
D03*
X-3559Y-191600D02*
D03*
X-1559Y-243600D02*
D03*
X-3559Y-351600D02*
D03*
X-5559Y-139600D02*
D03*
X-7559Y-143600D02*
D03*
Y-167600D02*
D03*
Y-191600D02*
D03*
Y-199600D02*
D03*
Y-223600D02*
D03*
X-5559Y-227600D02*
D03*
Y-243600D02*
D03*
X-7559Y-247600D02*
D03*
Y-279600D02*
D03*
X-5559Y-299600D02*
D03*
X-7559Y-303600D02*
D03*
Y-327600D02*
D03*
Y-351600D02*
D03*
X-9559Y-139600D02*
D03*
Y-171600D02*
D03*
X-11559Y-191600D02*
D03*
X-9559Y-195600D02*
D03*
Y-227600D02*
D03*
Y-243600D02*
D03*
X-11559Y-247600D02*
D03*
X-9559Y-251600D02*
D03*
Y-275600D02*
D03*
X-11559Y-279600D02*
D03*
X-9559Y-299600D02*
D03*
Y-331600D02*
D03*
X-11559Y-351600D02*
D03*
X-13559Y-139600D02*
D03*
X-15559Y-191600D02*
D03*
X-13559Y-243600D02*
D03*
X-15559Y-351600D02*
D03*
X-19559Y-263600D02*
D03*
Y-351600D02*
D03*
X-23559Y-159600D02*
D03*
Y-191600D02*
D03*
X-21559Y-211600D02*
D03*
X-23559Y-263600D02*
D03*
X-21559Y-315600D02*
D03*
X-23559Y-351600D02*
D03*
X-25559Y-139600D02*
D03*
Y-155600D02*
D03*
Y-211600D02*
D03*
Y-259600D02*
D03*
Y-267600D02*
D03*
Y-299600D02*
D03*
Y-315600D02*
D03*
X269685Y-136843D02*
D03*
X234252Y-133742D02*
D03*
X263779Y-106151D02*
D03*
X71850Y-147638D02*
D03*
X75787Y-131890D02*
D03*
X643701Y-63976D02*
D03*
X644685Y-45276D02*
D03*
X623000Y-37402D02*
D03*
X610236Y-8858D02*
D03*
X609252Y-26575D02*
D03*
X98425Y-102362D02*
D03*
X89567D02*
D03*
X85630Y-313976D02*
D03*
X86614Y-258858D02*
D03*
X81693Y-205709D02*
D03*
X86614Y-110236D02*
D03*
X63976Y-227362D02*
D03*
X68898Y-285433D02*
D03*
X67913Y-340551D02*
D03*
X68573Y-179321D02*
D03*
X44291Y-252953D02*
D03*
Y-272638D02*
D03*
Y-326772D02*
D03*
Y-307087D02*
D03*
X26575Y-291339D02*
D03*
X31496Y-189961D02*
D03*
X44291Y-147638D02*
D03*
Y-167323D02*
D03*
Y-200787D02*
D03*
Y-220472D02*
D03*
X570727Y-105662D02*
D03*
X103409Y-141732D02*
D03*
X103347Y-110236D02*
D03*
X119095Y-126047D02*
D03*
X494095Y-137647D02*
D03*
X518701Y-104214D02*
D03*
X519587Y-134596D02*
D03*
X528543Y-104214D02*
D03*
X114173Y-83088D02*
D03*
X441929Y-122883D02*
D03*
X256890Y-124852D02*
D03*
Y-121899D02*
D03*
X250000Y-120915D02*
D03*
X129921Y-79576D02*
D03*
X473425Y-125836D02*
D03*
X473425Y-123868D02*
D03*
X473425Y-121899D02*
D03*
X505905Y-137647D02*
D03*
X163071Y-390730D02*
D03*
X632432Y-132480D02*
D03*
X614321Y-118307D02*
D03*
X99410Y-50049D02*
D03*
X632432Y-141142D02*
D03*
X259285Y-390247D02*
D03*
X267204Y-390009D02*
D03*
X216162Y-390947D02*
D03*
X235144Y-390416D02*
D03*
X251456Y-390009D02*
D03*
X226063Y-390722D02*
D03*
X281201Y-390009D02*
D03*
X174941Y-390600D02*
D03*
X202441D02*
D03*
X538813Y-144506D02*
D03*
X544813Y-109806D02*
D03*
X566813Y-132405D02*
D03*
D171*
X99016Y-121653D02*
D03*
X103347D02*
D03*
X107677D02*
D03*
X99016Y-125984D02*
D03*
X103347D02*
D03*
X107677D02*
D03*
X99016Y-130315D02*
D03*
X103347D02*
D03*
X107677D02*
D03*
M02*
